G04 ================== begin FILE IDENTIFICATION RECORD ==================*
G04 Layout Name:  F:/<user>/2022/FB/R4006-TIMING/brd/gerber-3/R4006-B0001-02_R01.brd*
G04 Film Name:    R4006-B0001-02_R01_TPM*
G04 File Format:  Gerber RS274X*
G04 File Origin:  Cadence Allegro 17.2-S079*
G04 Origin Date:  Fri Feb 25 18:14:43 2022*
G04 *
G04 Layer:  PACKAGE GEOMETRY/SOLDERPASTE_TOP*
G04 Layer:  PACKAGE GEOMETRY/PASTEMASK_TOP*
G04 Layer:  PIN/PASTEMASK_TOP*
G04 Layer:  VIA CLASS/PASTEMASK_TOP*
G04 Layer:  MANUFACTURING/CELESTICA_LEGEND*
G04 Layer:  MANUFACTURING/SOLDERPASTE_TOP*
G04 *
G04 Offset:    (0.00 0.00)*
G04 Mirror:    No*
G04 Mode:      Positive*
G04 Rotation:  0*
G04 FullContactRelief:  No*
G04 UndefLineWidth:     6.00*
G04 ================== end FILE IDENTIFICATION RECORD ====================*
%FSLAX55Y55*MOIN*%
%IR0*IPPOS*OFA0.00000B0.00000*MIA0B0*SFA1.00000B1.00000*%
%AMMACRO67*
4,1,6,.0105,.00452,
.0105,.0205,
-.0105,.0205,
-.0105,-.0205,
.0015,-.0205,
.0015,.00452,
.0105,.00452,
0.0*
%
%ADD67MACRO67*%
%AMMACRO35*
4,1,6,.00452,-.0105,
.0205,-.0105,
.0205,.0105,
-.0205,.0105,
-.0205,-.0015,
.00452,-.0015,
.00452,-.0105,
0.0*
%
%ADD35MACRO35*%
%AMMACRO66*
4,1,6,.0105,-.00452,
.0105,-.0205,
-.0105,-.0205,
-.0105,.0205,
.0015,.0205,
.0015,-.00452,
.0105,-.00452,
0.0*
%
%ADD66MACRO66*%
%ADD53R,.14X.05*%
%AMMACRO46*
4,1,6,-.00452,-.0105,
-.0205,-.0105,
-.0205,.0105,
.0205,.0105,
.0205,-.0015,
-.00452,-.0015,
-.00452,-.0105,
0.0*
%
%ADD46MACRO46*%
%ADD20R,.05X.14*%
%ADD77R,.104X.045*%
%ADD79R,.045X.104*%
%ADD80R,.094X.13*%
%ADD27R,.063X.118*%
%ADD57R,.008X.053*%
%ADD56R,.037X.008*%
%ADD38R,.02X.02*%
%ADD81R,.031X.031*%
%ADD52R,.146X.096*%
%ADD48R,.096X.146*%
%ADD62C,.0197*%
%AMMACRO91*
4,1,8,.02619,.02281,
.02619,-.02281,
.01319,-.02281,
.01319,.01295,
-.01319,.01295,
-.01319,-.02281,
-.02619,-.02281,
-.02619,.02281,
.02619,.02281,
0.0*
%
%ADD91MACRO91*%
%AMMACRO65*
4,1,6,-.0105,-.00452,
-.0105,-.0205,
.0105,-.0205,
.0105,.0205,
-.0015,.0205,
-.0015,-.00452,
-.0105,-.00452,
0.0*
%
%ADD65MACRO65*%
%AMMACRO47*
4,1,6,-.00452,.0105,
-.0205,.0105,
-.0205,-.0105,
.0205,-.0105,
.0205,.0015,
-.00452,.0015,
-.00452,.0105,
0.0*
%
%ADD47MACRO47*%
%AMMACRO64*
4,1,6,-.0105,.00452,
-.0105,.0205,
.0105,.0205,
.0105,-.0205,
-.0015,-.0205,
-.0015,.00452,
-.0105,.00452,
0.0*
%
%ADD64MACRO64*%
%AMMACRO37*
4,1,6,.00452,.0105,
.0205,.0105,
.0205,-.0105,
-.0205,-.0105,
-.0205,.0015,
.00452,.0015,
.00452,.0105,
0.0*
%
%ADD37MACRO37*%
%ADD54R,.01X.023*%
%ADD45R,.024X.01*%
%ADD88R,.01X.024*%
%ADD63R,.012X.041*%
%ADD41R,.024X.02*%
%ADD25R,.011X.014*%
%ADD24R,.014X.011*%
%ADD89R,.02X.024*%
%ADD60R,.015X.012*%
%ADD50R,.071X.01*%
%ADD43R,.012X.024*%
%ADD36R,.041X.012*%
%ADD84R,.024X.012*%
%ADD73R,.033X.012*%
%ADD18R,.034X.03*%
%ADD16R,.012X.015*%
%ADD55R,.027X.01*%
%ADD29R,.03X.034*%
%ADD11R,.02X.018*%
%ADD59R,.072X.02*%
%ADD42R,.012X.045*%
%ADD92R,.013X.044*%
%ADD82R,.045X.012*%
%ADD51R,.062X.014*%
%ADD34R,.065X.02*%
%ADD30R,.064X.012*%
%ADD28R,.047X.02*%
%ADD19R,.014X.062*%
%ADD71R,.046X.012*%
%ADD70R,.012X.046*%
%ADD68R,.017X.024*%
%ADD31R,.012X.064*%
%ADD26R,.02X.047*%
%ADD15R,.012X.038*%
%ADD10R,.035X.033*%
%ADD97R,.053X.016*%
%ADD94R,.06X.018*%
%ADD86R,.138X.116*%
%ADD85R,.047X.012*%
%ADD75R,.033X.017*%
%ADD74R,.025X.035*%
%ADD49R,.038X.013*%
%ADD44R,.106X.008*%
%ADD87R,.008X.106*%
%ADD58R,.055X.033*%
%ADD40R,.016X.045*%
%ADD23R,.018X.06*%
%ADD14R,.024X.028*%
%ADD83R,.045X.016*%
%ADD72R,.049X.012*%
%ADD69R,.012X.049*%
%ADD17R,.028X.024*%
%ADD22R,.039X.041*%
%ADD13R,.043X.057*%
%ADD78R,.088X.04*%
%ADD33R,.054X.038*%
%ADD39R,.038X.054*%
%ADD21R,.041X.087*%
%ADD95R,.092X.056*%
%ADD90R,.001X.001*%
%ADD61R,.055X.039*%
%ADD32R,.055X.047*%
%ADD76R,.039X.055*%
%ADD12R,.039X.057*%
%ADD96R,.075X.059*%
%ADD93R,.088X.056*%
%ADD98C,.01*%
%ADD99C,.005*%
%ADD100C,.006*%
G75*
%LPD*%
G75*
G36*
G01X22807Y334235D02*
G02Y337735I0J1750D01*
G01X26807D01*
G02Y334235I0J-1750D01*
G01X22807D01*
G37*
G36*
G01Y345495D02*
G02Y348995I0J1750D01*
G01X26807D01*
G02Y345495I0J-1750D01*
G01X22807D01*
G37*
G36*
G01X24034Y340080D02*
G03I-1200J0D01*
G37*
G36*
G01X25806Y343150D02*
G03I-1200J0D01*
G37*
G36*
G01X27578Y340080D02*
G03I-1200J0D01*
G37*
G36*
G01X29350Y343150D02*
G03I-1200J0D01*
G37*
G36*
G01X41705Y329905D02*
G02Y333405I0J1750D01*
G01X45705D01*
G02Y329905I0J-1750D01*
G01X41705D01*
G37*
G36*
G01Y349826D02*
G02Y353326I0J1750D01*
G01X45705D01*
G02Y349826I0J-1750D01*
G01X41705D01*
G37*
G36*
G01X31122Y340080D02*
G03I-1200J0D01*
G37*
G36*
G01X32894Y343150D02*
G03I-1200J0D01*
G37*
G36*
G01X34666Y340080D02*
G03I-1200J0D01*
G37*
G36*
G01X36438Y343150D02*
G03I-1200J0D01*
G37*
G36*
G01X38210Y340080D02*
G03I-1200J0D01*
G37*
G36*
G01X39982Y343150D02*
G03I-1200J0D01*
G37*
G36*
G01X43526D02*
G03I-1200J0D01*
G37*
G36*
G01X41754Y340080D02*
G03I-1200J0D01*
G37*
G36*
G01X45298D02*
G03I-1200J0D01*
G37*
G36*
G01X47070Y343150D02*
G03I-1200J0D01*
G37*
G36*
G01X66900Y393840D02*
X70367D01*
G03X70820Y393323I933J360D01*
G01Y389600D01*
X66900D01*
Y393840D01*
G37*
G36*
G01X72233D02*
X75067D01*
G03X75540Y393312I933J360D01*
G01Y389600D01*
X71620D01*
Y393253D01*
G03X72233Y393840I-320J947D01*
G37*
G36*
G01X76933D02*
X79767D01*
G03X80260Y393302I933J360D01*
G01Y389600D01*
X76340D01*
Y393260D01*
G03X76933Y393840I-340J940D01*
G37*
G36*
G01X76947Y398880D02*
X79753D01*
G03X80260Y398302I947J320D01*
G01Y395098D01*
G03X79802Y394640I440J-898D01*
G01X76898D01*
G03X76340Y395140I-898J-440D01*
G01Y398260D01*
G03X76947Y398880I-340J940D01*
G37*
G36*
G01X72247D02*
X75053D01*
G03X75540Y398312I947J320D01*
G01Y395088D01*
G03X75102Y394640I460J-888D01*
G01X72198D01*
G03X71620Y395147I-898J-440D01*
G01Y398253D01*
G03X72247Y398880I-320J947D01*
G37*
G36*
G01X66900D02*
X70353D01*
G03X70820Y398323I947J320D01*
G01Y395077D01*
G03X70402Y394640I480J-877D01*
G01X66900D01*
Y398880D01*
G37*
G36*
G01X76960Y403920D02*
X79740D01*
G03X80260Y403302I960J280D01*
G01Y400098D01*
G03X79823Y399680I440J-898D01*
G01X76877D01*
G03X76340Y400140I-877J-480D01*
G01Y403260D01*
G03X76960Y403920I-340J940D01*
G37*
G36*
G01X72260D02*
X75040D01*
G03X75540Y403312I960J280D01*
G01Y400088D01*
G03X75123Y399680I460J-888D01*
G01X72177D01*
G03X71620Y400147I-877J-480D01*
G01Y403253D01*
G03X72260Y403920I-320J947D01*
G37*
G36*
G01X66900D02*
X70340D01*
G03X70820Y403323I960J280D01*
G01Y400077D01*
G03X70423Y399680I480J-877D01*
G01X66900D01*
Y403920D01*
G37*
G36*
G01X76971Y408960D02*
X79729D01*
G03X80260Y408302I971J240D01*
G01Y404720D01*
X76340D01*
Y408260D01*
G03X76971Y408960I-340J941D01*
G37*
G36*
G01X66900D02*
X70329D01*
G03X70820Y408323I971J240D01*
G01Y405077D01*
G03X70446Y404720I480J-877D01*
G01X66900D01*
Y408960D01*
G37*
G36*
G01X72271D02*
X75029D01*
G03X75540Y408312I971J240D01*
G01Y405088D01*
G03X75146Y404720I460J-888D01*
G01X72154D01*
G03X71620Y405147I-854J-520D01*
G01Y408253D01*
G03X72271Y408960I-320J947D01*
G37*
G36*
G01X76340Y414000D02*
X80260D01*
Y410098D01*
G03X79872Y409760I441J-898D01*
G01X76828D01*
G03X76340Y410140I-828J-560D01*
G01Y414000D01*
G37*
G36*
G01X71620D02*
X75540D01*
Y410088D01*
G03X75172Y409760I461J-887D01*
G01X72128D01*
G03X71620Y410147I-828J-560D01*
G01Y414000D01*
G37*
G36*
G01X66900D02*
X70820D01*
Y410077D01*
G03X70472Y409760I480J-877D01*
G01X66900D01*
Y414000D01*
G37*
G36*
G01X81633Y393840D02*
X84467D01*
G03X84980Y393292I933J360D01*
G01Y389600D01*
X81060D01*
Y393267D01*
G03X81633Y393840I-360J933D01*
G37*
G36*
G01X86333D02*
X89700D01*
Y389600D01*
X85780D01*
Y393275D01*
G03X86333Y393840I-380J925D01*
G37*
G36*
G01X86347Y398880D02*
X89700D01*
Y394640D01*
X86298D01*
G03X85780Y395125I-898J-440D01*
G01Y398275D01*
G03X86347Y398880I-380J925D01*
G37*
G36*
G01X81647D02*
X84453D01*
G03X84980Y398292I948J319D01*
G01Y395108D01*
G03X84502Y394640I420J-907D01*
G01X81598D01*
G03X81060Y395133I-898J-440D01*
G01Y398267D01*
G03X81647Y398880I-360J933D01*
G37*
G36*
G01X86360Y403920D02*
X89700D01*
Y399680D01*
X86277D01*
G03X85780Y400125I-877J-480D01*
G01Y403275D01*
G03X86360Y403920I-380J925D01*
G37*
G36*
G01X81660D02*
X84440D01*
G03X84980Y403292I960J280D01*
G01Y400108D01*
G03X84523Y399680I421J-907D01*
G01X81577D01*
G03X81060Y400133I-877J-480D01*
G01Y403267D01*
G03X81660Y403920I-360J933D01*
G37*
G36*
G01X86371Y408960D02*
X89700D01*
Y404720D01*
X86254D01*
G03X85780Y405125I-854J-520D01*
G01Y408275D01*
G03X86371Y408960I-380J925D01*
G37*
G36*
G01X81671D02*
X84429D01*
G03X84980Y408292I971J240D01*
G01Y405108D01*
G03X84546Y404720I421J-907D01*
G01X81554D01*
G03X81060Y405133I-854J-520D01*
G01Y408267D01*
G03X81671Y408960I-360J933D01*
G37*
G36*
G01X85780Y414000D02*
X89700D01*
Y409760D01*
X86228D01*
G03X85780Y410125I-829J-560D01*
G01Y414000D01*
G37*
G36*
G01X81060D02*
X84980D01*
Y410108D01*
G03X84572Y409760I421J-907D01*
G01X81528D01*
G03X81060Y410133I-829J-560D01*
G01Y414000D01*
G37*
G36*
G01X131031Y104643D02*
X129971D01*
G03X126667Y107947I-3904J-600D01*
G01Y109007D01*
G02X131031Y104643I-600J-4964D01*
G37*
G36*
G01X126667Y99079D02*
Y100139D01*
G03X129971Y103443I-600J3904D01*
G01X131031D01*
G02X126667Y99079I-4964J600D01*
G37*
G36*
G01X121103Y103443D02*
X122163D01*
G03X125467Y100139I3904J600D01*
G01Y99079D01*
G02X121103Y103443I600J4964D01*
G37*
G36*
G01X125467Y109007D02*
Y107947D01*
G03X122163Y104643I600J-3904D01*
G01X121103D01*
G02X125467Y109007I4964J-600D01*
G37*
G36*
G01X126667Y179079D02*
Y180139D01*
G03X129971Y183443I-600J3904D01*
G01X131031D01*
G02X126667Y179079I-4964J600D01*
G37*
G36*
G01X121103Y183443D02*
X122163D01*
G03X125467Y180139I3904J600D01*
G01Y179079D01*
G02X121103Y183443I600J4964D01*
G37*
G36*
G01X131031Y184643D02*
X129971D01*
G03X126667Y187947I-3904J-600D01*
G01Y189007D01*
G02X131031Y184643I-600J-4964D01*
G37*
G36*
G01X125467Y189007D02*
Y187947D01*
G03X122163Y184643I600J-3904D01*
G01X121103D01*
G02X125467Y189007I4964J-600D01*
G37*
G36*
G01Y269007D02*
Y267947D01*
G03X122163Y264643I600J-3904D01*
G01X121103D01*
G02X125467Y269007I4964J-600D01*
G37*
G36*
G01X121103Y263443D02*
X122163D01*
G03X125467Y260139I3904J600D01*
G01Y259079D01*
G02X121103Y263443I600J4964D01*
G37*
G36*
G01X126667Y259079D02*
Y260139D01*
G03X129971Y263443I-600J3904D01*
G01X131031D01*
G02X126667Y259079I-4964J600D01*
G37*
G36*
G01X131031Y264643D02*
X129971D01*
G03X126667Y267947I-3904J-600D01*
G01Y269007D01*
G02X131031Y264643I-600J-4964D01*
G37*
G36*
G01X165150Y301900D02*
Y304050D01*
G03X166150Y305050I1000J0D01*
G01X170850D01*
Y301900D01*
X165150D01*
G37*
G36*
G01Y301100D02*
X170850D01*
Y299000D01*
X170849Y298999D01*
G03X169850Y299950I-999J-49D01*
G03X168850Y298950I0J-1000D01*
G03X169780Y297952I1000J0D01*
G01Y297950D01*
X165150D01*
Y301100D01*
G37*
G36*
G01X249003Y92843D02*
X250063D01*
G03X253367Y89539I3904J600D01*
G01Y88479D01*
G02X249003Y92843I600J4964D01*
G37*
G36*
G01X253367Y98407D02*
Y97347D01*
G03X250063Y94043I600J-3904D01*
G01X249003D01*
G02X253367Y98407I4964J-600D01*
G37*
G36*
G01X255306Y301368D02*
G02X247628Y309046I600J8278D01*
G01X243420D01*
G03X255306Y297160I12486J600D01*
G01Y301368D01*
G37*
G36*
G01X247628Y310246D02*
G02X255306Y317924I8278J-600D01*
G01Y322132D01*
G03X243420Y310246I600J-12486D01*
G01X247628D01*
G37*
G36*
G01X255306Y403730D02*
G02X247628Y411408I600J8278D01*
G01X243420D01*
G03X255306Y399522I12486J600D01*
G01Y403730D01*
G37*
G36*
G01X247628Y412608D02*
G02X255306Y420286I8278J-600D01*
G01Y424494D01*
G03X243420Y412608I600J-12486D01*
G01X247628D01*
G37*
G36*
G01X254567Y88479D02*
Y89539D01*
G03X257871Y92843I-600J3904D01*
G01X258931D01*
G02X254567Y88479I-4964J600D01*
G37*
G36*
G01X261003Y92843D02*
X262063D01*
G03X265367Y89539I3904J600D01*
G01Y88479D01*
G02X261003Y92843I600J4964D01*
G37*
G36*
G01X266567Y88479D02*
Y89539D01*
G03X269871Y92843I-600J3904D01*
G01X270931D01*
G02X266567Y88479I-4964J600D01*
G37*
G36*
G01X258931Y94043D02*
X257871D01*
G03X254567Y97347I-3904J-600D01*
G01Y98407D01*
G02X258931Y94043I-600J-4964D01*
G37*
G36*
G01X265367Y98407D02*
Y97347D01*
G03X262063Y94043I600J-3904D01*
G01X261003D01*
G02X265367Y98407I4964J-600D01*
G37*
G36*
G01X270931Y94043D02*
X269871D01*
G03X266567Y97347I-3904J-600D01*
G01Y98407D01*
G02X270931Y94043I-600J-4964D01*
G37*
G36*
G01X264184Y309046D02*
G02X256506Y301368I-8278J600D01*
G01Y297160D01*
G03X268392Y309046I-600J12486D01*
G01X264184D01*
G37*
G36*
G01X256506Y317924D02*
G02X264184Y310246I-600J-8278D01*
G01X268392D01*
G03X256506Y322132I-12486J-600D01*
G01Y317924D01*
G37*
G36*
G01X264184Y411408D02*
G02X256506Y403730I-8278J600D01*
G01Y399522D01*
G03X268392Y411408I-600J12486D01*
G01X264184D01*
G37*
G36*
G01X256506Y420286D02*
G02X264184Y412608I-600J-8278D01*
G01X268392D01*
G03X256506Y424494I-12486J-600D01*
G01Y420286D01*
G37*
G36*
G01X272903Y92843D02*
X273963D01*
G03X277267Y89539I3904J600D01*
G01Y88479D01*
G02X272903Y92843I600J4964D01*
G37*
G36*
G01X278467Y88479D02*
Y89539D01*
G03X281771Y92843I-600J3904D01*
G01X282831D01*
G02X278467Y88479I-4964J600D01*
G37*
G36*
G01X277267Y98407D02*
Y97347D01*
G03X273963Y94043I600J-3904D01*
G01X272903D01*
G02X277267Y98407I4964J-600D01*
G37*
G36*
G01X282831Y94043D02*
X281771D01*
G03X278467Y97347I-3904J-600D01*
G01Y98407D01*
G02X282831Y94043I-600J-4964D01*
G37*
G36*
G01X291031Y104643D02*
X289971D01*
G03X286667Y107947I-3904J-600D01*
G01Y109007D01*
G02X291031Y104643I-600J-4964D01*
G37*
G36*
G01X286667Y99079D02*
Y100139D01*
G03X289971Y103443I-600J3904D01*
G01X291031D01*
G02X286667Y99079I-4964J600D01*
G37*
G36*
G01X281103Y103443D02*
X282163D01*
G03X285467Y100139I3904J600D01*
G01Y99079D01*
G02X281103Y103443I600J4964D01*
G37*
G36*
G01X285467Y109007D02*
Y107947D01*
G03X282163Y104643I600J-3904D01*
G01X281103D01*
G02X285467Y109007I4964J-600D01*
G37*
G36*
G01Y269007D02*
Y267947D01*
G03X282163Y264643I600J-3904D01*
G01X281103D01*
G02X285467Y269007I4964J-600D01*
G37*
G36*
G01X281103Y263443D02*
X282163D01*
G03X285467Y260139I3904J600D01*
G01Y259079D01*
G02X281103Y263443I600J4964D01*
G37*
G36*
G01X286667Y259079D02*
Y260139D01*
G03X289971Y263443I-600J3904D01*
G01X291031D01*
G02X286667Y259079I-4964J600D01*
G37*
G36*
G01X291031Y264643D02*
X289971D01*
G03X286667Y267947I-3904J-600D01*
G01Y269007D01*
G02X291031Y264643I-600J-4964D01*
G37*
G36*
G01X390800Y291650D02*
X388650D01*
G03X387650Y292650I0J1000D01*
G01Y297350D01*
X390800D01*
Y291650D01*
G37*
G36*
G01X409660Y404950D02*
X411950D01*
Y402167D01*
G03X411433Y401650I400J-917D01*
G01X408650D01*
Y403900D01*
X408651D01*
G03X409650Y402950I999J50D01*
G03X410650Y403950I0J1000D01*
G03X409660Y404950I-1000J0D01*
G37*
G36*
G01X408650Y396750D02*
X411433D01*
G03X411950Y396233I917J400D01*
G01Y393450D01*
X409670D01*
G03X410650Y394450I-20J1000D01*
G03X409650Y395450I-1000J0D01*
G03X408652Y394510I0J-1000D01*
G01X408650D01*
Y396750D01*
G37*
G36*
G01Y400850D02*
X411433D01*
G03X411950Y400333I917J400D01*
G01Y397550D01*
X408650D01*
Y400850D01*
G37*
G36*
G01X416850Y404950D02*
X419110D01*
X419111Y404949D01*
G03X418150Y403950I39J-999D01*
G03X419150Y402950I1000J0D01*
G03X420150Y403930I0J1000D01*
G01Y401650D01*
X417367D01*
G03X416850Y402167I-917J-400D01*
G01Y404950D01*
G37*
G36*
G01X417367Y396750D02*
X420150D01*
Y394460D01*
G03X419150Y395450I-1000J-10D01*
G03X418150Y394450I0J-1000D01*
G03X419130Y393450I1000J0D01*
G01X416850D01*
Y396233D01*
G03X417367Y396750I-400J917D01*
G37*
G36*
G01X413267D02*
X415533D01*
G03X416050Y396233I917J400D01*
G01Y393450D01*
X412750D01*
Y396233D01*
G03X413267Y396750I-400J917D01*
G37*
G36*
G01X417367Y400850D02*
X420150D01*
Y397550D01*
X417367D01*
G03X416850Y398067I-917J-400D01*
G01Y400333D01*
G03X417367Y400850I-400J917D01*
G37*
G36*
G01X412750Y404950D02*
X416050D01*
Y402167D01*
G03X415533Y401650I400J-917D01*
G01X413267D01*
G03X412750Y402167I-917J-400D01*
G01Y404950D01*
G37*
G36*
G01X413267Y400850D02*
X415533D01*
G03X416050Y400333I917J400D01*
G01Y398067D01*
G03X415533Y397550I400J-917D01*
G01X413267D01*
G03X412750Y398067I-917J-400D01*
G01Y400333D01*
G03X413267Y400850I-400J917D01*
G37*
G36*
G01X439150Y287200D02*
Y283800D01*
G03X438150Y282800I-1000J0D01*
G01X436000D01*
Y287200D01*
X439150D01*
G37*
G36*
G01X432050Y288000D02*
Y291400D01*
G03X433050Y292400I1000J0D01*
G01X435200D01*
Y288000D01*
X432050D01*
G37*
G36*
G01X502372Y309046D02*
G02X494694Y301368I-8278J600D01*
G01Y297160D01*
G03X506580Y309046I-600J12486D01*
G01X502372D01*
G37*
G36*
G01X493494Y301368D02*
G02X485816Y309046I600J8278D01*
G01X481608D01*
G03X493494Y297160I12486J600D01*
G01Y301368D01*
G37*
G36*
G01X494694Y317924D02*
G02X502372Y310246I-600J-8278D01*
G01X506580D01*
G03X494694Y322132I-12486J-600D01*
G01Y317924D01*
G37*
G36*
G01X485816Y310246D02*
G02X493494Y317924I8278J-600D01*
G01Y322132D01*
G03X481608Y310246I600J-12486D01*
G01X485816D01*
G37*
G36*
G01X493494Y403730D02*
G02X485816Y411408I600J8278D01*
G01X481608D01*
G03X493494Y399522I12486J600D01*
G01Y403730D01*
G37*
G36*
G01X502372Y411408D02*
G02X494694Y403730I-8278J600D01*
G01Y399522D01*
G03X506580Y411408I-600J12486D01*
G01X502372D01*
G37*
G36*
G01X485816Y412608D02*
G02X493494Y420286I8278J-600D01*
G01Y424494D01*
G03X481608Y412608I600J-12486D01*
G01X485816D01*
G37*
G36*
G01X494694Y420286D02*
G02X502372Y412608I-600J-8278D01*
G01X506580D01*
G03X494694Y424494I-12486J-600D01*
G01Y420286D01*
G37*
G36*
G01X513650Y270300D02*
Y268150D01*
G03X512650Y267150I-1000J0D01*
G01X507950D01*
Y270300D01*
X513650D01*
G37*
G36*
G01X508970Y274250D02*
X513650D01*
Y271100D01*
X507950D01*
Y273230D01*
G03X508950Y272250I1000J20D01*
G03X509950Y273250I0J1000D01*
G03X508970Y274250I-1000J0D01*
G37*
G36*
G01X559650Y68300D02*
Y70450D01*
G03X560650Y71450I1000J0D01*
G01X565350D01*
Y68300D01*
X559650D01*
G37*
G36*
G01Y67500D02*
X565350D01*
Y65420D01*
X565348Y65418D01*
G03X564350Y66350I-998J-68D01*
G03X563350Y65350I0J-1000D01*
G03X564290Y64352I1000J0D01*
G01Y64350D01*
X559650D01*
Y67500D01*
G37*
G36*
G01X596490Y211350D02*
X598600D01*
Y207450D01*
X595450D01*
Y210290D01*
X595452D01*
G03X596450Y209350I998J60D01*
G03X597450Y210350I0J1000D01*
G03X596490Y211349I-1000J0D01*
G01Y211350D01*
G37*
G36*
G01X599400D02*
X602550D01*
Y208530D01*
X602547Y208527D01*
G03X601550Y209450I-997J-77D01*
G03X600550Y208450I0J-1000D01*
G03X601460Y207454I1000J0D01*
G01Y207450D01*
X599400D01*
Y211350D01*
G37*
G36*
G01X394750Y291650D02*
X391600D01*
Y297350D01*
X394750D01*
Y291650D01*
G37*
G36*
G01X435200Y287200D02*
Y282800D01*
X432050D01*
Y287200D01*
X435200D01*
G37*
G36*
G01X439150Y292400D02*
Y288000D01*
X436000D01*
Y292400D01*
X439150D01*
G37*
G36*
G01X556050Y373413D02*
Y372413D01*
X551150D01*
Y373413D01*
X556050D01*
G37*
G36*
G01Y369869D02*
Y368869D01*
X551150D01*
Y369869D01*
X556050D01*
G37*
G36*
G01Y380499D02*
Y379499D01*
X551150D01*
Y380499D01*
X556050D01*
G37*
G36*
G01Y376956D02*
Y375956D01*
X551150D01*
Y376956D01*
X556050D01*
G37*
G54D100*
G01X145964Y-110118D02*
G03I-634J0D01*
G01X149695D02*
G03I-1038J0D01*
G01X168013Y-137456D02*
G03I-634J0D01*
G01X155900Y-133655D02*
G03I-632J0D01*
G01X161735Y-128639D02*
G03I-1458J0D01*
G01X158530Y-131428D02*
G03I-1041J0D01*
G01X158461Y-119126D02*
G03I-1283J0D01*
G01X162690Y-117490D02*
G03I-1584J0D01*
G01X169809Y-121292D02*
G03I-2180J0D01*
G01X165531Y-125255D02*
G03I-1869J0D01*
G01X167813Y-115513D02*
G03I-1971J0D01*
G01X154775Y-120500D02*
G03I-892J0D01*
G01X162681Y-102774D02*
G03I-1584J0D01*
G01X158451Y-101149D02*
G03I-1283J0D01*
G01X159258Y-110118D02*
G03I-1868J0D01*
G01X169812Y-98951D02*
G03I-2180J0D01*
G01X167802Y-104739D02*
G03I-1971J0D01*
G01X165183Y-110118D02*
G03I-2180J0D01*
G01X171881D02*
G03I-2642J0D01*
G01X152135Y-98681D02*
G03I-632J0D01*
G01X154064Y-110118D02*
G03I-1460J0D01*
G01X154764Y-99775D02*
G03I-892J0D01*
G01X158530Y-88809D02*
G03I-1041J0D01*
G01X161742Y-91601D02*
G03I-1458J0D01*
G01X165531Y-94981D02*
G03I-1869J0D01*
G01X171080Y-131739D02*
G03I-1282J0D01*
G01X169322Y-135033D02*
G03I-892J0D01*
G01X180669Y-131528D02*
G03I-1870J0D01*
G01X180255Y-136311D02*
G03I-1456J0D01*
G01X179841Y-140261D02*
G03I-1042J0D01*
G01X179433Y-143587D02*
G03I-634J0D01*
G01X181439Y-119680D02*
G03I-2640J0D01*
G01X175373Y-123081D02*
G03I-1968J0D01*
G01X173018Y-127816D02*
G03I-1584J0D01*
G01X174681Y-116876D02*
G03I-2640J0D01*
G01X180979Y-125917D02*
G03I-2180J0D01*
G01X186177Y-123075D02*
G03I-1971J0D01*
G01X188199Y-116876D02*
G03I-2640J0D01*
G01X175452Y-97124D02*
G03I-1968J0D01*
G01X186225Y-97178D02*
G03I-1971J0D01*
G01X181439Y-100556D02*
G03I-2640J0D01*
G01X174681Y-103361D02*
G03I-2640J0D01*
G01X188199D02*
G03I-2640J0D01*
G01X179841Y-79975D02*
G03I-1042J0D01*
G01X171217Y-88444D02*
G03I-1282J0D01*
G01X173123Y-92378D02*
G03I-1584J0D01*
G01X180255Y-83924D02*
G03I-1456J0D01*
G01X180669Y-88708D02*
G03I-1870J0D01*
G01X180979Y-94320D02*
G03I-2180J0D01*
G01X179433Y-76648D02*
G03I-634J0D01*
G01X191096Y-134658D02*
G03I-892J0D01*
G01X192135Y-136781D02*
G03I-631J0D01*
G01X198775Y-128635D02*
G03I-1458J0D01*
G01X195808Y-125255D02*
G03I-1869J0D01*
G01X200547Y-113952D02*
G03X203345Y-117196I7247J3422D01*
G01X192148Y-121285D02*
G03I-2180J0D01*
G01X187928Y-127802D02*
G03I-1584J0D01*
G01X189667Y-131511D02*
G03I-1283J0D01*
G01X200699Y-105836D02*
G03X200547Y-113953I8974J-4228D01*
G01X208284Y-101612D02*
G03X200698Y-105835I-219J-8531D01*
G01X192148Y-98951D02*
G03I-2180J0D01*
G01X191108Y-82727D02*
G03I-634J0D01*
G01X190184Y-85250D02*
G03I-893J0D01*
G01X195808Y-94981D02*
G03I-1869J0D01*
G01X187839Y-92457D02*
G03I-1584J0D01*
G01X189190Y-88538D02*
G03I-1283J0D01*
G01X214259Y-115661D02*
G03X213314Y-114453I-714J415D01*
G01X202049Y-108260D02*
G03X205722Y-116181I7039J-1548D01*
G01X218075Y-112869D02*
G03X219083Y-115752I4343J-99D01*
G01X208854Y-116658D02*
G03X213313Y-114452I-2485J10632D01*
G01X208470Y-118462D02*
G03X214261Y-115663I-1122J9711D01*
G01X203346Y-117195D02*
G03X208470Y-118461I4545J7394D01*
G01X205721Y-116179D02*
G03X208853Y-116659I2561J6250D01*
G01X215903Y-114020D02*
G03X219079Y-118061I6190J1597D01*
G01X215904Y-114020D02*
Y-111835D01*
G01X227413Y-112869D02*
X218074D01*
G01X214175Y-103951D02*
G03X208283Y-101613I-6403J-7542D01*
G01X213150Y-105147D02*
G03X214175Y-103951I410J686D01*
G01X213152Y-105146D02*
G03X208030Y-103430I-5122J-6786D01*
G01X208029Y-103429D02*
G03X202049Y-108259I-48J-6058D01*
G01X225189Y-111399D02*
G03X218071I-3559J159D01*
G01X218070Y-111418D02*
Y-111399D01*
G01X225188Y-111418D02*
X218070D01*
G01X227412Y-111835D02*
G03X215906I-5753J223D01*
G01X230059Y-117625D02*
Y-102034D01*
G01X230060Y-117626D02*
G03X232080I1010J239D01*
G01X226590Y-116472D02*
G03X225311Y-115210I-817J451D01*
G01X234673Y-114020D02*
G03X237849Y-118061I6190J1597D01*
G01X232081Y-102041D02*
Y-117625D01*
G01X219083Y-115753D02*
G03X225311Y-115211I2844J3371D01*
G01X219079Y-118060D02*
G03X226591Y-116473I2662J5972D01*
G01X227413Y-111835D02*
Y-112869D01*
G01X232080Y-102041D02*
G03X230060Y-102034I-1011J-236D01*
G01X225188Y-111399D02*
Y-111418D01*
G01X234675Y-114020D02*
Y-111835D01*
G01X246181D02*
G03X234675I-5753J223D01*
G01X252849Y-116771D02*
G03X254892Y-115895I-74J2994D01*
G01X236844Y-112869D02*
G03X237852Y-115752I4343J-99D01*
G01X237848Y-118060D02*
G03X245360Y-116473I2662J5972D01*
G01X245358Y-116472D02*
G03X244079Y-115210I-817J451D01*
G01X237852Y-115753D02*
G03X244080Y-115211I2844J3371D01*
G01X249566Y-115529D02*
G03X252307Y-116760I2985J2980D01*
G01Y-116761D02*
G03X252849Y-116772I366J4691D01*
G01X250282Y-118087D02*
G03X254318Y-118340I2605J9244D01*
G01X247897Y-116444D02*
G03X250283Y-118086I3752J2898D01*
G01X249568Y-115529D02*
G03X247898Y-116443I-748J-616D01*
G01X255608Y-108618D02*
G03X253612Y-107689I-3116J-4086D01*
G01X246181Y-111835D02*
Y-112869D01*
G01D02*
X236844D01*
G01X255002Y-114328D02*
G03X252723Y-112986I-3540J-3405D01*
G01X249955Y-112030D02*
G03X252723Y-112985I8208J19302D01*
G01X243957Y-111399D02*
Y-111418D01*
G01X243958Y-111399D02*
G03X236840I-3559J159D01*
G01X236841Y-111418D02*
Y-111399D01*
G01X243957Y-111418D02*
X236841D01*
G01X248537Y-109748D02*
G03X249956Y-112031I2652J66D01*
G01X248537Y-108250D02*
Y-109748D01*
G01X250179Y-106359D02*
G03X248537Y-108249I2747J-4045D01*
G01X256884Y-107368D02*
G03X250178Y-106359I-4153J-4811D01*
G01X253611Y-107689D02*
G03X251080Y-107949I-869J-3992D01*
G01X251081Y-107948D02*
G03X250837Y-110104I805J-1183D01*
G01Y-110106D02*
G03X254306Y-111513I5270J8013D01*
G01X260954Y-116041D02*
Y-107954D01*
G01X254892Y-115895D02*
G03X255001Y-114328I-764J840D01*
G01X269619Y-117484D02*
Y-106797D01*
G01X269620Y-117484D02*
G03X271926I1153J198D01*
G01X266864Y-117375D02*
G03X266002Y-116329I-764J249D01*
G01X262978Y-115462D02*
G03X266002Y-116329I2046J1428D01*
G01X260955Y-116043D02*
G03X264164Y-118351I2956J725D01*
G01X265463Y-118350D02*
X264165D01*
G01X265464Y-118352D02*
G03X266864Y-117374I-24J1525D01*
G01X256906Y-116470D02*
G03X257054Y-113728I-3143J1545D01*
G01X254317Y-118340D02*
G03X256906Y-116470I-1259J4470D01*
G01X262978Y-107954D02*
Y-115463D01*
G01X257054Y-113729D02*
G03X254307Y-111513I-3470J-1490D01*
G01X271969Y-102342D02*
G03I-1194J0D01*
G01X271926Y-106797D02*
G03X269620I-1153J-409D01*
G01X266003Y-107954D02*
X262978D01*
G01X266004Y-107955D02*
G03X266008Y-105932I-177J1012D01*
G01X262978D02*
X266008D01*
G01X262971Y-103419D02*
X262978Y-105932D01*
G01X262972Y-103418D02*
G03X260954Y-103491I-1005J-141D01*
G01Y-105932D02*
Y-103492D01*
G01X259930Y-105932D02*
X260954D01*
G01X259930D02*
G03X259981Y-107955I298J-1005D01*
G01X260954Y-107954D02*
X259982D01*
G01X255606Y-108620D02*
G03X256885Y-107367I599J667D01*
G01X290671Y-110842D02*
G03X290703Y-118351I860J-3751D01*
G01X276837Y-114305D02*
G03X278891Y-116297I4069J2141D01*
G01X274529Y-113568D02*
G03X275888Y-116443I5718J944D01*
G01X275887D02*
G03X279572Y-118352I4392J3967D01*
G01X281425Y-118350D02*
X279571D01*
G01X281425D02*
G03X284525Y-117161I0J4636D01*
G01X285201Y-116508D02*
X284524Y-117161D01*
G01X285201Y-116508D02*
G03X283966Y-115211I-695J574D01*
G01X281510Y-116675D02*
G03X283966Y-115212I-989J4453D01*
G01X278889Y-116297D02*
G03X281508Y-116677I1946J4197D01*
G01X271926Y-106797D02*
Y-117484D01*
G01X274529Y-113566D02*
Y-111839D01*
G01X276446Y-112943D02*
G03X276837Y-114305I4162J458D01*
G01X276445Y-112066D02*
Y-112943D01*
G01X283833Y-109274D02*
G03X285403Y-108106I585J852D01*
G01X285402D02*
G03X280919Y-105777I-4776J-3714D01*
G01X279541D02*
X280919D01*
G01X279540D02*
G03X274999Y-109274I1260J-6333D01*
G01X274998D02*
G03X274529Y-111839I9988J-3152D01*
G01X276849Y-109932D02*
G03X276446Y-112066I5467J-2137D01*
G01X280036Y-107542D02*
G03X276849Y-109933I664J-4205D01*
G01X282662Y-108199D02*
G03X280037Y-107539I-2313J-3650D01*
G01X283833Y-109275D02*
G03X282662Y-108202I-9277J-8949D01*
G01X294457Y-116619D02*
G03Y-112289I-51J2165D01*
G01X291853Y-116620D02*
X294456D01*
G01X291853Y-112289D02*
G03Y-116619I195J-2165D01*
G01X294165Y-118350D02*
X290701D01*
G01X294165D02*
G03X296471Y-117226I-1088J5161D01*
G01X296473Y-117625D02*
Y-117226D01*
G01X296474Y-117627D02*
G03X298494I1010J185D01*
G01X298495Y-109394D02*
Y-117625D01*
G01X301067Y-108534D02*
Y-106508D01*
G01X301615Y-108534D02*
X301067D01*
G01X301615Y-106508D02*
Y-108534D01*
G01X302461Y-106508D02*
X301615D01*
G01X302461Y-106001D02*
Y-106508D01*
G01X300223Y-106001D02*
X302461D01*
G01X300223Y-106508D02*
Y-106001D01*
G01X301067Y-106508D02*
X300223D01*
G01X305164Y-106001D02*
X304731D01*
G01X305713Y-108544D02*
X305164Y-106001D01*
G01X305171Y-108544D02*
X305713D01*
G01X304889Y-106871D02*
X305171Y-108544D01*
G01X304309D02*
X304889Y-106871D01*
G01X304086Y-108544D02*
X304309D01*
G01X303501Y-106887D02*
X304086Y-108544D01*
G01X303226D02*
X303501Y-106887D01*
G01X302698Y-108544D02*
X303226D01*
G01X303243Y-106001D02*
X302698Y-108544D01*
G01X303648Y-106001D02*
X303243D01*
G01X304192Y-107632D02*
X303648Y-106001D01*
G01X304731D02*
X304192Y-107632D01*
G01X294456Y-112288D02*
X291853D01*
G01X296473Y-110841D02*
Y-109686D01*
G01X296472Y-110841D02*
G03X292878Y-110536I-3256J-17043D01*
G01X292879Y-110535D02*
G03X290670Y-110842I280J-10112D01*
G01X298496Y-109394D02*
G03X295031Y-105933I-3962J-501D01*
G01X291563Y-105932D02*
X295031D01*
G01X291562D02*
G03X289112Y-107085I584J-4421D01*
G01Y-107086D02*
G03X289820Y-108520I585J-603D01*
G01X290987Y-107954D02*
G03X289821Y-108520I1446J-4464D01*
G01X294740Y-107954D02*
X290987D01*
G01X296473Y-109686D02*
G03X294742Y-107955I-1598J133D01*
G01X380900Y-131934D02*
X381700Y-132600D01*
X382600Y-133000D01*
X383400D01*
X384200Y-132600D01*
X384800Y-131934D01*
X385100Y-131000D01*
X384900Y-130067D01*
X384400Y-129267D01*
X383500Y-128733D01*
X382300Y-128467D01*
X381600Y-127933D01*
X381300Y-127000D01*
X381500Y-126067D01*
X382000Y-125400D01*
X382700Y-125000D01*
X383400D01*
X384100Y-125267D01*
X384700Y-125933D01*
G01X391000Y-133000D02*
X390200Y-132867D01*
X389500Y-132333D01*
X388900Y-131533D01*
X388500Y-130600D01*
X388300Y-129533D01*
Y-128467D01*
X388500Y-127400D01*
X388900Y-126467D01*
X389500Y-125667D01*
X390200Y-125133D01*
X391000Y-125000D01*
X391800Y-125133D01*
X392500Y-125667D01*
X393100Y-126467D01*
X393500Y-127400D01*
X393700Y-128467D01*
Y-129533D01*
X393500Y-130600D01*
X393100Y-131533D01*
X392500Y-132333D01*
X391800Y-132867D01*
X391000Y-133000D01*
G01X397000Y-125000D02*
Y-133000D01*
X401000D01*
G01X404800D02*
Y-125000D01*
X406800D01*
X407600Y-125400D01*
X408200Y-125933D01*
X408700Y-126733D01*
X409100Y-127667D01*
X409200Y-129000D01*
X409100Y-130333D01*
X408700Y-131267D01*
X408200Y-132067D01*
X407600Y-132600D01*
X406800Y-133000D01*
X404800D01*
G01X417000D02*
X413000D01*
Y-125000D01*
X417000D01*
G01X415400Y-128867D02*
X413000D01*
G01X421000Y-133000D02*
Y-125000D01*
X423500D01*
X424300Y-125400D01*
X424800Y-125933D01*
X425000Y-127000D01*
X424800Y-128067D01*
X424200Y-128733D01*
X423500Y-129133D01*
X421000D01*
G01X423500D02*
X425000Y-133000D01*
G01X429000D02*
Y-125000D01*
X431400D01*
X432200Y-125400D01*
X432800Y-126333D01*
X433000Y-127400D01*
X432800Y-128467D01*
X432300Y-129267D01*
X431400Y-129667D01*
X429000D01*
G01X436500Y-133000D02*
X439000Y-125000D01*
X441500Y-133000D01*
G01X440600Y-130200D02*
X437400D01*
G01X444900Y-131934D02*
X445700Y-132600D01*
X446600Y-133000D01*
X447400D01*
X448200Y-132600D01*
X448800Y-131934D01*
X449100Y-131000D01*
X448900Y-130067D01*
X448400Y-129267D01*
X447500Y-128733D01*
X446300Y-128467D01*
X445600Y-127933D01*
X445300Y-127000D01*
X445500Y-126067D01*
X446000Y-125400D01*
X446700Y-125000D01*
X447400D01*
X448100Y-125267D01*
X448700Y-125933D01*
G01X455000Y-125000D02*
Y-133000D01*
G01X452700Y-125000D02*
X457300D01*
G01X465000Y-133000D02*
X461000D01*
Y-125000D01*
X465000D01*
G01X463400Y-128867D02*
X461000D01*
G01X468000Y-135667D02*
X474000D01*
G01X479000Y-125000D02*
Y-133000D01*
G01X476700Y-125000D02*
X481300D01*
G01X487000Y-133000D02*
X486200Y-132867D01*
X485500Y-132333D01*
X484900Y-131533D01*
X484500Y-130600D01*
X484300Y-129533D01*
Y-128467D01*
X484500Y-127400D01*
X484900Y-126467D01*
X485500Y-125667D01*
X486200Y-125133D01*
X487000Y-125000D01*
X487800Y-125133D01*
X488500Y-125667D01*
X489100Y-126467D01*
X489500Y-127400D01*
X489700Y-128467D01*
Y-129533D01*
X489500Y-130600D01*
X489100Y-131533D01*
X488500Y-132333D01*
X487800Y-132867D01*
X487000Y-133000D01*
G01X493000D02*
Y-125000D01*
X495400D01*
X496200Y-125400D01*
X496800Y-126333D01*
X497000Y-127400D01*
X496800Y-128467D01*
X496300Y-129267D01*
X495400Y-129667D01*
X493000D01*
G54D10*
X6874Y91633D03*
Y102067D03*
Y159154D03*
Y148720D03*
Y216241D03*
Y205807D03*
Y262893D03*
Y273327D03*
Y319980D03*
Y330414D03*
G54D11*
X8252Y98523D03*
Y95177D03*
Y155610D03*
Y152264D03*
Y212697D03*
Y209351D03*
Y266437D03*
Y269783D03*
Y326870D03*
Y323524D03*
G54D20*
X70500Y142244D03*
X80500D03*
X70500Y162756D03*
X80500D03*
G54D12*
X27250Y95650D03*
X19750Y104350D03*
X27250D03*
X19750Y218350D03*
X27250D03*
Y209650D03*
G54D21*
X74593Y209100D03*
X86207D03*
G54D30*
X89400Y320136D03*
Y337853D03*
Y335884D03*
Y333916D03*
Y331947D03*
Y329979D03*
Y328010D03*
Y326042D03*
Y324073D03*
Y322105D03*
Y349664D03*
Y347695D03*
Y345727D03*
Y343758D03*
Y341790D03*
Y339821D03*
X135200Y320136D03*
Y322105D03*
Y324073D03*
Y326042D03*
Y328010D03*
Y329979D03*
Y331947D03*
Y333916D03*
Y335884D03*
Y337853D03*
Y345727D03*
Y347695D03*
Y349664D03*
Y339821D03*
Y341790D03*
Y343758D03*
G54D13*
X20550Y95650D03*
Y209650D03*
G54D22*
X80400Y215104D03*
G54D40*
X163222Y391187D03*
Y402013D03*
X336678Y395787D03*
Y406613D03*
G54D31*
X97536Y312000D03*
Y357800D03*
X113284Y312000D03*
X111316D03*
X109347D03*
X107379D03*
X105410D03*
X103442D03*
X101473D03*
X99505D03*
Y357800D03*
X101473D03*
X103442D03*
X105410D03*
X107379D03*
X109347D03*
X111316D03*
X113284D03*
X127064Y312000D03*
X125095D03*
X123127D03*
X121158D03*
X119190D03*
X117221D03*
X115253D03*
Y357800D03*
X117221D03*
X119190D03*
X121158D03*
X123127D03*
X125095D03*
X127064D03*
G54D32*
X129831Y385154D03*
X121169D03*
Y391846D03*
X129831D03*
G54D14*
X28100Y156898D03*
Y152698D03*
X23600Y156898D03*
Y152698D03*
X19100Y156898D03*
Y152698D03*
X24200Y266408D03*
X19700D03*
X24200Y270608D03*
X19700D03*
X18000Y318900D03*
X23000D03*
X28000D03*
X18000Y323100D03*
X23000D03*
X28000D03*
X44300Y64700D03*
Y68900D03*
X45500Y108390D03*
Y112590D03*
Y117800D03*
Y122000D03*
X32600Y156898D03*
Y152698D03*
X37100Y156898D03*
Y152698D03*
X41600Y156898D03*
Y152698D03*
X45500Y164400D03*
Y178100D03*
Y173900D03*
Y168600D03*
X45200Y232600D03*
Y236800D03*
X37700Y266408D03*
X42200D03*
X33200D03*
X28700D03*
X37700Y270608D03*
X42200D03*
X33200D03*
X28700D03*
X43000Y318900D03*
X38000D03*
X33000D03*
X43000Y323100D03*
X38000D03*
X33000D03*
X58000Y88400D03*
Y92600D03*
X48500D03*
Y88400D03*
X53500D03*
Y92600D03*
X62500Y108400D03*
Y112600D03*
X50500Y112590D03*
Y108390D03*
X58000Y144400D03*
X48000D03*
X53000D03*
X60600Y164745D03*
X58000Y148600D03*
X48000D03*
X53000D03*
X60600Y168945D03*
X57500Y204900D03*
Y209100D03*
X48000D03*
Y204900D03*
X53000D03*
Y209100D03*
X51452Y227500D03*
Y223300D03*
X46452D03*
Y227500D03*
X57800Y256900D03*
Y261100D03*
X47800D03*
Y256900D03*
X53000Y258400D03*
Y262600D03*
X59500Y355400D03*
Y359600D03*
X71400Y225200D03*
Y229400D03*
X64000Y222900D03*
Y227100D03*
X71500Y244400D03*
Y240200D03*
X76948Y252500D03*
Y256700D03*
X80648Y283100D03*
Y278900D03*
X83500Y252400D03*
Y256600D03*
X107500Y293900D03*
Y298100D03*
X112500Y293900D03*
Y298100D03*
X102500D03*
Y293900D03*
X110500Y368900D03*
Y373100D03*
X115500Y368900D03*
Y373100D03*
X105500Y368900D03*
Y373100D03*
X117500Y293900D03*
Y298100D03*
X144500Y370400D03*
Y374600D03*
X138500Y408400D03*
Y412600D03*
X154800Y66320D03*
Y62120D03*
X153000Y300400D03*
X151000Y320600D03*
Y316400D03*
X153000Y304600D03*
X155600Y416200D03*
Y412000D03*
X183500Y293900D03*
Y298100D03*
X199770Y59000D03*
Y63200D03*
X188500Y298100D03*
Y293900D03*
X195900Y324700D03*
Y328900D03*
X210500Y59400D03*
X215000D03*
X204770Y59000D03*
X210500Y63600D03*
X215000D03*
X204770Y63200D03*
X217300Y297300D03*
Y293100D03*
X212800Y297300D03*
Y293100D03*
X208300Y297300D03*
Y293100D03*
X217600Y384500D03*
Y388700D03*
X221800Y297300D03*
Y293100D03*
X226280Y328700D03*
Y324500D03*
X251122Y58400D03*
Y62600D03*
X325900Y196900D03*
Y201100D03*
Y206400D03*
Y210600D03*
X338484Y251100D03*
X333500D03*
X328500D03*
X338484Y255300D03*
X333500D03*
X328500D03*
X325500Y370600D03*
Y366400D03*
X357500Y162100D03*
Y157900D03*
X355400Y178749D03*
Y174549D03*
X354600Y251300D03*
X343500Y251100D03*
X354600Y255500D03*
X343500Y255300D03*
X358200Y285600D03*
Y276100D03*
Y280300D03*
Y289800D03*
X344300Y381600D03*
Y385800D03*
X377000Y87400D03*
Y91600D03*
X360400Y174549D03*
Y178749D03*
X370500Y238400D03*
Y242600D03*
X376000D03*
Y238400D03*
X366200Y297600D03*
Y301800D03*
X362300Y387800D03*
Y383600D03*
X391900Y251000D03*
X386000D03*
X380100D03*
X391900Y255200D03*
X386000D03*
X380100D03*
X379700Y284900D03*
Y296900D03*
Y301100D03*
Y289100D03*
X387000Y346600D03*
Y342400D03*
X401000Y107100D03*
Y102900D03*
X405500Y107100D03*
Y102900D03*
X403700Y251000D03*
X397800D03*
X409300D03*
X403700Y255200D03*
X397800D03*
X409300D03*
X408000Y347100D03*
Y342900D03*
X420500Y87900D03*
Y92100D03*
X420900Y251000D03*
X415000D03*
X420900Y255200D03*
X415000D03*
X436900Y107300D03*
Y103100D03*
X441400Y107300D03*
Y103100D03*
X439500Y241900D03*
Y246100D03*
X444000D03*
Y241900D03*
X439000Y269900D03*
Y274100D03*
X434000Y345400D03*
Y349600D03*
X458500Y113900D03*
Y118100D03*
X453000Y113900D03*
Y118100D03*
X453500Y232400D03*
X457500Y246100D03*
Y241900D03*
X448500Y246100D03*
Y241900D03*
X453500Y236600D03*
X453000Y246100D03*
Y241900D03*
X462000Y246100D03*
Y241900D03*
X453000Y389100D03*
Y384900D03*
X465000Y234100D03*
Y229900D03*
X473500Y350400D03*
Y354600D03*
X478500Y350400D03*
Y354600D03*
X496100Y268600D03*
X496000Y263600D03*
Y259400D03*
X488900Y268600D03*
X496100Y272800D03*
X488900D03*
X488500Y354600D03*
Y350400D03*
X483500D03*
Y354600D03*
X498500D03*
Y350400D03*
X493500Y354600D03*
Y350400D03*
X533100Y223800D03*
Y228000D03*
X527800Y265300D03*
Y261100D03*
X532800Y265300D03*
Y261100D03*
X527000Y276900D03*
Y281100D03*
X531500D03*
Y276900D03*
X541000Y179400D03*
Y183600D03*
X545000Y208900D03*
Y213100D03*
X546500Y232400D03*
Y236600D03*
X564000Y94400D03*
Y98600D03*
X555500Y232400D03*
X560000D03*
X555500Y236600D03*
X560000D03*
X577200Y65800D03*
Y70000D03*
X577500Y75400D03*
Y79600D03*
X570000Y210900D03*
Y215100D03*
X575400Y232400D03*
Y236600D03*
X591902Y195065D03*
Y190865D03*
X596902Y195065D03*
Y190865D03*
X601902D03*
Y195065D03*
X606902D03*
Y190865D03*
X614100Y227800D03*
Y232000D03*
X628900Y197074D03*
Y201274D03*
G54D23*
X78260Y224650D03*
Y242750D03*
X85940Y224650D03*
X83380D03*
X80820D03*
X83380Y242750D03*
X80820D03*
X85940D03*
X209660Y308450D03*
X212220D03*
X214780D03*
X217340D03*
X209660Y326550D03*
X212220D03*
X214780D03*
X217340D03*
G54D50*
X276986Y175184D03*
Y177152D03*
Y179121D03*
Y181089D03*
Y185026D03*
Y186995D03*
Y188963D03*
Y190932D03*
Y183058D03*
Y192900D03*
X292734Y175184D03*
Y177152D03*
Y179121D03*
Y181089D03*
Y186995D03*
Y188963D03*
Y190932D03*
Y192900D03*
Y183058D03*
Y185026D03*
G54D41*
X158104Y391187D03*
Y402013D03*
X341796Y395787D03*
Y406613D03*
G54D33*
X146000Y300700D03*
Y307300D03*
X218600Y403800D03*
Y410400D03*
X223600Y382800D03*
Y389400D03*
X226100Y403800D03*
Y410400D03*
X340000Y371800D03*
Y365200D03*
X332000Y371800D03*
Y365200D03*
X351500Y164800D03*
Y158200D03*
X348000Y371800D03*
Y365200D03*
X370500Y164800D03*
Y158200D03*
X372900Y287000D03*
Y280400D03*
X373200Y295200D03*
Y301800D03*
X445500Y267200D03*
Y273800D03*
X505000Y383700D03*
Y390300D03*
X535000Y178700D03*
Y185300D03*
X525400Y373800D03*
Y367200D03*
X533600Y373800D03*
Y367200D03*
X539000Y159700D03*
Y166300D03*
X538500Y205700D03*
Y212300D03*
X557500Y93200D03*
Y99800D03*
X576000Y208700D03*
Y215300D03*
X622500Y197074D03*
Y203674D03*
G54D15*
X57676Y64606D03*
X51772Y77914D03*
X53740D03*
X55708Y64606D03*
X51772D03*
X53740D03*
X57676Y77914D03*
X55708D03*
X57676Y121692D03*
X55708D03*
X51772D03*
X53740D03*
X51772Y135000D03*
X53740D03*
X57676D03*
X55708D03*
X57676Y178779D03*
X55708D03*
X51772D03*
X53740D03*
X51772Y192087D03*
X53740D03*
X57676D03*
X55708D03*
X57676Y235866D03*
X51772Y249174D03*
X53740D03*
X55708Y235866D03*
X51772D03*
X53740D03*
X57676Y249174D03*
X55708D03*
G54D51*
X304250Y322543D03*
Y325102D03*
Y335339D03*
Y327661D03*
Y332780D03*
Y337898D03*
Y330220D03*
Y340457D03*
X328150Y335339D03*
Y330220D03*
Y337898D03*
Y332780D03*
Y327661D03*
Y325102D03*
Y322543D03*
Y340457D03*
X403550Y358543D03*
Y361102D03*
Y363661D03*
Y366220D03*
Y368780D03*
Y371339D03*
Y373898D03*
Y376457D03*
X416950Y306643D03*
Y309202D03*
Y311761D03*
Y314320D03*
Y316880D03*
Y319439D03*
Y321998D03*
Y324557D03*
X427450Y371339D03*
Y368780D03*
Y366220D03*
Y363661D03*
Y361102D03*
Y358543D03*
Y376457D03*
Y373898D03*
X440850Y319439D03*
Y316880D03*
Y314320D03*
Y311761D03*
Y309202D03*
Y306643D03*
Y324557D03*
Y321998D03*
X488550Y74043D03*
Y76602D03*
Y79161D03*
Y81720D03*
Y84280D03*
Y86839D03*
Y89398D03*
Y91957D03*
X512450Y76602D03*
Y74043D03*
Y91957D03*
Y89398D03*
Y86839D03*
Y84280D03*
Y81720D03*
Y79161D03*
G54D42*
X165781Y391187D03*
Y402013D03*
X170112Y391187D03*
X167946D03*
Y402013D03*
X170112D03*
X334119Y395787D03*
X331954D03*
X329788D03*
Y406613D03*
X331954D03*
X334119D03*
G54D60*
X363673Y232557D03*
Y234643D03*
Y241243D03*
Y239157D03*
X398200Y310043D03*
Y307957D03*
X551000Y232957D03*
Y235043D03*
X564000Y232957D03*
Y235043D03*
X569500Y233457D03*
Y235543D03*
G54D24*
X75897Y266100D03*
Y264131D03*
Y268069D03*
X81999D03*
Y266100D03*
Y264131D03*
G54D61*
X388000Y75217D03*
Y89783D03*
X398000Y75217D03*
X408000D03*
Y89783D03*
X398000D03*
G54D70*
X408494Y389540D03*
Y408860D03*
X420306Y389540D03*
Y408860D03*
G54D34*
X166220Y59000D03*
Y64000D03*
Y69000D03*
Y74000D03*
X188320Y59000D03*
Y64000D03*
Y69000D03*
Y74000D03*
G54D16*
X52443Y100000D03*
X50357D03*
X48957Y157000D03*
X51043D03*
X49557Y216600D03*
X51643D03*
X51743Y268000D03*
X49657D03*
X123543Y379000D03*
X121457D03*
X126957D03*
X129043D03*
X147143Y390100D03*
X145057D03*
Y403100D03*
X147143D03*
X146643Y408600D03*
X144557D03*
X171457Y290000D03*
X173543D03*
X352757Y389200D03*
X354843D03*
Y394700D03*
X352757D03*
X352657Y412100D03*
X354743D03*
X394157Y277400D03*
X396243D03*
X495257Y277700D03*
X497343D03*
X529043Y272500D03*
X526957D03*
X543957Y63500D03*
X546043D03*
X548557Y391200D03*
X550643D03*
X578043Y60900D03*
X575957D03*
X571057Y371200D03*
X573143D03*
G54D43*
X160860Y390104D03*
Y403096D03*
X339040Y407696D03*
Y394704D03*
G54D25*
X79932Y263049D03*
X77964D03*
Y269151D03*
X79932D03*
G54D52*
X305000Y374787D03*
Y398213D03*
G54D17*
X55600Y165000D03*
X51400D03*
X61900Y279000D03*
X63100Y329000D03*
X58900D03*
X77900Y110000D03*
Y105000D03*
Y120000D03*
Y125000D03*
Y115000D03*
Y130000D03*
X74547Y179500D03*
X78747D03*
X74547Y175000D03*
X78747D03*
X74547Y193000D03*
X78747D03*
X74547Y197500D03*
X78747D03*
X74547Y188500D03*
X78747D03*
X74547Y184000D03*
X78747D03*
X68448Y266400D03*
X64248D03*
Y261400D03*
X68448D03*
X71400Y279000D03*
X75600D03*
X64248Y270900D03*
X68448D03*
X66100Y279000D03*
X70400Y320000D03*
X74600D03*
X70400Y324500D03*
X74600D03*
X82100Y110000D03*
Y105000D03*
Y120000D03*
Y125000D03*
Y115000D03*
Y130000D03*
X90700Y258048D03*
X94900D03*
X95048Y268300D03*
X90848D03*
X95100Y272800D03*
X90900D03*
X121570Y61360D03*
X117370D03*
Y65860D03*
X121570D03*
X117370Y75360D03*
X121570D03*
X117370Y70860D03*
X121570D03*
X130850Y65800D03*
Y61300D03*
X130870Y70800D03*
Y75300D03*
X122900Y375000D03*
X127100D03*
X135050Y65800D03*
Y61300D03*
X135070Y70800D03*
Y75300D03*
X148400Y295000D03*
X142500Y385100D03*
X146700D03*
X143500Y399100D03*
X147700D03*
X143500Y394600D03*
X147700D03*
Y414200D03*
X143500D03*
X152600Y295000D03*
X167000Y384100D03*
X165000Y409100D03*
X182400Y304000D03*
X181900Y319000D03*
X171200Y384100D03*
X169200Y409100D03*
X186600Y304000D03*
X186100Y319000D03*
X263700Y60500D03*
X259500D03*
Y65500D03*
X263700D03*
X289500Y320600D03*
Y325900D03*
X289600Y333200D03*
X299600Y57441D03*
X295400D03*
X299720Y66780D03*
X295520D03*
X299700Y62100D03*
X295500D03*
X293700Y320600D03*
Y325900D03*
X293800Y333200D03*
X312400Y164500D03*
X316600D03*
X312300Y180000D03*
X316500D03*
X316600Y169500D03*
X312400D03*
X312300Y175000D03*
X316500D03*
X316800Y196500D03*
X321000D03*
X316100Y189500D03*
X311900D03*
X316100Y185000D03*
X311900D03*
X316800Y201500D03*
X321000D03*
X316800Y206000D03*
X321000D03*
X316800Y211000D03*
X321000D03*
X315900Y216400D03*
X320100D03*
X315900Y220900D03*
X320100D03*
X315900Y234400D03*
X320100D03*
X315900Y229900D03*
X320100D03*
Y225400D03*
X315900D03*
Y247900D03*
X320100D03*
Y238900D03*
X315900D03*
X320100Y243400D03*
X315900D03*
Y252400D03*
X320100D03*
X315900Y256900D03*
X320100D03*
X329600Y216500D03*
X325400D03*
X330700Y388700D03*
X334900D03*
X328700Y413700D03*
X332900D03*
X352200Y383300D03*
X356400D03*
X349400Y378000D03*
X353600D03*
X356400Y403200D03*
X352200D03*
X356400Y398700D03*
X352200D03*
X356400Y407700D03*
X352200D03*
X359400Y419700D03*
X355200D03*
X376900Y97000D03*
X373100Y271000D03*
X368900D03*
X391100Y97000D03*
X386900D03*
X381100D03*
X392600Y268000D03*
X385800D03*
X381600D03*
X385800Y277500D03*
X381600D03*
X392600Y272500D03*
X385800D03*
X381600D03*
X393300Y309200D03*
X389100D03*
X383500D03*
X379300D03*
X383900Y381000D03*
X388100D03*
X383900Y375800D03*
X388100D03*
X410100Y97000D03*
X405900D03*
X396400D03*
X400600D03*
X396800Y268000D03*
Y272500D03*
X401500Y329100D03*
X397300D03*
X401500Y323900D03*
X397300D03*
X414500Y279200D03*
X418700D03*
X432200Y97300D03*
X436400D03*
X446000D03*
X441800D03*
X432450Y112300D03*
X436650D03*
X445850D03*
X441650D03*
X442600Y370000D03*
X438400D03*
X442600Y379000D03*
X438400D03*
X435400Y386500D03*
X439600D03*
X442600Y374500D03*
X438400D03*
X439600Y396500D03*
X435400D03*
X439600Y401500D03*
X435400D03*
Y391500D03*
X439600D03*
X435400Y406500D03*
X439600D03*
X435400Y411500D03*
X439600D03*
X456600Y284500D03*
X452400D03*
X456600Y289500D03*
X452400D03*
X456600Y294500D03*
X452400D03*
Y299500D03*
X456600D03*
X455100Y327000D03*
X450900D03*
X451200Y322000D03*
X455400D03*
X473600Y86500D03*
X469400D03*
X473600Y78500D03*
X469400D03*
X473600Y91500D03*
X469400D03*
X473600Y96500D03*
X469400D03*
X495900Y138500D03*
Y143000D03*
Y133500D03*
X488400Y163000D03*
X492600D03*
X488400Y167500D03*
X492600D03*
X488400Y176500D03*
X492600D03*
Y172000D03*
X488400D03*
Y197500D03*
X492600D03*
X488400Y211500D03*
X492600D03*
X488400Y202500D03*
X492600D03*
X488400Y207000D03*
X492600D03*
X500100Y138500D03*
Y143000D03*
Y133500D03*
X505600Y247400D03*
X501400D03*
X508400Y259700D03*
X504200D03*
X516200Y259200D03*
X508900Y377500D03*
X513100D03*
X524900Y76000D03*
X529100D03*
Y92000D03*
X524900D03*
Y82000D03*
X529100D03*
X524900Y87000D03*
X529100D03*
X520400Y259200D03*
X532000Y395700D03*
X544600Y69000D03*
X540400D03*
X546443Y396700D03*
X550643D03*
X536200Y395700D03*
X564900Y79200D03*
X569100D03*
X556900D03*
X552700D03*
X565400Y240000D03*
X563700Y356900D03*
X559500D03*
X560100Y391500D03*
X555900D03*
Y396000D03*
X560100D03*
X577100Y224500D03*
X572900D03*
X569600Y240000D03*
X576200Y351700D03*
X572000D03*
Y346700D03*
X576200D03*
Y356700D03*
X572000D03*
Y366700D03*
X576200D03*
X572000Y361700D03*
X576200D03*
Y385700D03*
X572000D03*
X576200Y380700D03*
X572000D03*
Y390700D03*
X576200D03*
X572000Y375700D03*
X576200D03*
X595600Y108000D03*
X591400D03*
X595600Y96500D03*
X591400D03*
Y112500D03*
X595600D03*
Y102500D03*
X591400D03*
X602900Y227000D03*
Y222500D03*
X594153Y223900D03*
X589953D03*
Y228402D03*
X594153D03*
X589953Y233000D03*
X594153D03*
X607100Y227000D03*
Y222500D03*
X637900Y96500D03*
Y102000D03*
Y108000D03*
Y113500D03*
X642100Y96500D03*
Y102000D03*
Y108000D03*
Y113500D03*
G54D44*
X166962Y397880D03*
Y395320D03*
X332938Y399920D03*
Y402480D03*
G54D26*
X75740Y339350D03*
X72000D03*
X68260D03*
Y350650D03*
X72000D03*
X75740D03*
X373240Y251350D03*
X369500D03*
X365760D03*
Y262650D03*
X369500D03*
X373240D03*
X630729Y220184D03*
X626989D03*
X623249D03*
Y231484D03*
X626989D03*
X630729D03*
G54D71*
X404740Y393294D03*
Y405106D03*
X424060D03*
Y393294D03*
G54D62*
X389161Y141035D03*
Y137098D03*
X393098Y141035D03*
Y137098D03*
Y133161D03*
X389161D03*
X393098Y144973D03*
X389161D03*
X393098Y156784D03*
Y148910D03*
X389161Y156784D03*
Y148910D03*
X393098Y152847D03*
X389161D03*
X393098Y160721D03*
X389161D03*
X393098Y164658D03*
Y172532D03*
X389161Y164658D03*
Y176469D03*
X393098D03*
X389161Y172532D03*
X393098Y180406D03*
X389161D03*
X393098Y168595D03*
X389161D03*
X393098Y184343D03*
X389161Y196154D03*
Y188280D03*
Y192217D03*
X393098Y188280D03*
Y192217D03*
Y196154D03*
X389161Y184343D03*
Y215839D03*
X393098Y204028D03*
Y211902D03*
X389161D03*
X393098Y215839D03*
X389161Y200091D03*
Y204028D03*
X393098Y207965D03*
X389161D03*
X393098Y200091D03*
X408847Y137098D03*
X397035Y133161D03*
Y144973D03*
X404910D03*
X400973D03*
Y141035D03*
X397035D03*
X408847D03*
X404910D03*
X408847Y133161D03*
X404910Y137098D03*
X400973D03*
X404910Y133161D03*
X400973D03*
X397035Y137098D03*
X408847Y144973D03*
X397035Y160721D03*
X408847Y156784D03*
X404910Y160721D03*
X400973Y152847D03*
X408847Y148910D03*
X404910Y156784D03*
Y148910D03*
X400973Y160721D03*
X397035Y152847D03*
X408847Y160721D03*
Y152847D03*
X404910D03*
X400973Y156784D03*
Y148910D03*
X397035Y156784D03*
Y148910D03*
X408847Y176469D03*
X404910D03*
X408847Y164658D03*
X400973Y168595D03*
X408847Y172532D03*
X404910Y164658D03*
Y172532D03*
X400973Y180406D03*
Y176469D03*
X397035D03*
Y168595D03*
Y180406D03*
X404910D03*
X408847D03*
Y168595D03*
X404910D03*
X400973Y164658D03*
Y172532D03*
X397035Y164658D03*
Y172532D03*
X404910Y188280D03*
X408847Y196154D03*
X397035Y192217D03*
X400973Y184343D03*
Y188280D03*
X404910Y192217D03*
X400973D03*
X404910Y184343D03*
X397035D03*
Y188280D03*
X408847Y192217D03*
X404910Y196154D03*
X408847Y184343D03*
X400973Y196154D03*
X397035D03*
X408847Y188280D03*
Y215839D03*
X400973Y200091D03*
X397035Y211902D03*
X404910Y207965D03*
Y211902D03*
X400973D03*
X404910Y215839D03*
X400973D03*
X397035D03*
X400973Y207965D03*
X397035D03*
X408847Y204028D03*
Y207965D03*
Y200091D03*
X404910D03*
Y204028D03*
X400973D03*
X397035Y200091D03*
Y204028D03*
X408847Y211902D03*
X420658Y141035D03*
X428532Y137098D03*
X416721Y133161D03*
X424595Y137098D03*
X420658D03*
X416721D03*
X412784D03*
X424595Y133161D03*
X420658D03*
X412784D03*
X428532Y144973D03*
Y133161D03*
Y141035D03*
X424595D03*
Y144973D03*
X420658D03*
X416721D03*
X412784D03*
X416721Y141035D03*
X412784D03*
X416721Y152847D03*
X428532Y156784D03*
X424595Y160721D03*
X420658Y156784D03*
X416721Y160721D03*
X428532D03*
X424595Y156784D03*
Y148910D03*
X420658Y160721D03*
X416721Y156784D03*
X412784Y160721D03*
Y156784D03*
Y152847D03*
Y148910D03*
X428532D03*
X424595Y152847D03*
X420658D03*
Y148910D03*
X416721D03*
X428532Y152847D03*
X420658Y180406D03*
Y164658D03*
X416721Y168595D03*
X428532Y172532D03*
X420658D03*
X424595Y176469D03*
X416721D03*
X424595Y168595D03*
Y172532D03*
X420658Y176469D03*
Y168595D03*
X416721Y164658D03*
Y172532D03*
X412784Y164658D03*
Y176469D03*
Y168595D03*
X424595Y164658D03*
X428532Y180406D03*
X416721D03*
X412784D03*
X424595D03*
X428532Y164658D03*
Y168595D03*
X412784Y172532D03*
X428532Y176469D03*
Y196154D03*
X416721Y192217D03*
X424595Y188280D03*
X412784Y184343D03*
X416721Y196154D03*
X420658Y188280D03*
X416721D03*
X412784Y196154D03*
X420658Y184343D03*
X416721D03*
X412784Y188280D03*
Y192217D03*
X428532D03*
X424595D03*
X428532Y184343D03*
Y188280D03*
X424595Y196154D03*
X420658D03*
X424595Y184343D03*
X420658Y192217D03*
X424595Y207965D03*
X412784Y204028D03*
X428532Y215839D03*
X420658Y200091D03*
X416721Y211902D03*
X424595D03*
Y215839D03*
X416721Y207965D03*
X412784D03*
X420658Y215839D03*
X416721D03*
Y200091D03*
X412784D03*
Y211902D03*
Y215839D03*
X428532Y200091D03*
Y204028D03*
Y207965D03*
X424595Y200091D03*
Y204028D03*
X420658D03*
X416721D03*
X420658Y207965D03*
Y211902D03*
X428532D03*
X436406Y133161D03*
X432469Y144973D03*
X440343Y141035D03*
X444280D03*
Y137098D03*
X440343D03*
X436406D03*
X440343Y144973D03*
X444280Y133161D03*
X440343D03*
X436406Y144973D03*
Y141035D03*
X432469D03*
Y137098D03*
Y133161D03*
X444280Y144973D03*
Y148910D03*
X436406Y156784D03*
X432469Y160721D03*
X444280Y156784D03*
X440343Y160721D03*
X444280D03*
X440343Y156784D03*
X436406Y160721D03*
Y152847D03*
X432469Y156784D03*
X440343Y152847D03*
X436406Y148910D03*
X432469Y152847D03*
Y148910D03*
X440343D03*
X444280Y152847D03*
X440343Y168595D03*
X444280Y164658D03*
X436406Y172532D03*
X444280D03*
X440343Y176469D03*
X432469D03*
X444280D03*
Y168595D03*
X440343Y164658D03*
Y180406D03*
Y172532D03*
X432469D03*
Y180406D03*
X436406D03*
X432469Y168595D03*
Y164658D03*
X444280Y180406D03*
X436406Y176469D03*
Y168595D03*
Y164658D03*
X444280Y188280D03*
X432469Y184343D03*
X436406Y192217D03*
X432469Y188280D03*
Y192217D03*
Y196154D03*
X440343Y192217D03*
X444280Y196154D03*
X436406Y184343D03*
X440343Y188280D03*
X444280Y192217D03*
X436406Y196154D03*
X440343D03*
Y184343D03*
X444280D03*
X436406Y188280D03*
Y211902D03*
X440343Y200091D03*
X444280Y207965D03*
X432469Y204028D03*
X436406Y207965D03*
X432469D03*
X436406Y200091D03*
Y204028D03*
X432469Y200091D03*
X436406Y215839D03*
X432469D03*
Y211902D03*
X440343Y204028D03*
X444280D03*
X440343Y211902D03*
X444280D03*
Y200091D03*
X440343Y215839D03*
X444280D03*
X440343Y207965D03*
X460028Y141035D03*
X448217Y137098D03*
X456091Y133161D03*
X452154Y144973D03*
X463965Y141035D03*
X452154D03*
X456091D03*
X460028Y133161D03*
X463965D03*
X460028Y137098D03*
X463965D03*
X452154D03*
X456091D03*
X448217Y133161D03*
X452154D03*
X448217Y144973D03*
X456091D03*
X460028D03*
X463965D03*
X448217Y141035D03*
X456091Y152847D03*
X448217Y160721D03*
X463965Y148910D03*
X460028Y160721D03*
X448217Y156784D03*
X463965Y160721D03*
Y156784D03*
X456091Y160721D03*
Y156784D03*
X460028D03*
X463965Y152847D03*
X448217D03*
X452154D03*
X456091Y148910D03*
X460028Y152847D03*
Y148910D03*
X448217D03*
X452154D03*
Y156784D03*
Y160721D03*
X463965Y168595D03*
X460028Y180406D03*
X448217Y176469D03*
Y168595D03*
X456091Y172532D03*
X448217Y164658D03*
Y172532D03*
X460028Y164658D03*
X463965D03*
X456091D03*
X463965Y180406D03*
X456091D03*
X460028Y172532D03*
Y176469D03*
X463965Y172532D03*
Y176469D03*
X456091Y168595D03*
X460028D03*
X448217Y180406D03*
X452154D03*
X456091Y176469D03*
X452154Y164658D03*
Y168595D03*
Y172532D03*
Y176469D03*
X456091Y192217D03*
X463965Y188280D03*
X452154Y184343D03*
X448217Y196154D03*
X460028Y184343D03*
X463965D03*
Y192217D03*
X452154Y196154D03*
X448217Y192217D03*
X452154D03*
X456091Y196154D03*
X460028Y188280D03*
Y196154D03*
Y192217D03*
X448217Y184343D03*
Y188280D03*
X452154D03*
X456091D03*
Y184343D03*
X463965Y196154D03*
Y207965D03*
X452154Y204028D03*
X448217Y215839D03*
X460028Y200091D03*
X456091Y211902D03*
X463965D03*
Y215839D03*
X460028Y211902D03*
Y215839D03*
X448217Y204028D03*
Y207965D03*
Y211902D03*
X452154D03*
Y215839D03*
X456091D03*
X448217Y200091D03*
X452154D03*
X456091D03*
Y204028D03*
X463965Y200091D03*
Y204028D03*
X460028D03*
Y207965D03*
X452154D03*
X456091D03*
X471839Y144973D03*
X467902Y137098D03*
Y141035D03*
X471839D03*
Y137098D03*
X467902Y133161D03*
X471839D03*
X467902Y144973D03*
Y156784D03*
Y160721D03*
X471839D03*
Y156784D03*
Y152847D03*
X467902D03*
Y148910D03*
X471839D03*
X467902Y176469D03*
X471839Y164658D03*
X467902Y168595D03*
Y172532D03*
Y164658D03*
X471839Y168595D03*
Y172532D03*
Y176469D03*
X467902Y180406D03*
X471839D03*
Y184343D03*
X467902Y196154D03*
Y184343D03*
Y188280D03*
X471839D03*
Y192217D03*
Y196154D03*
X467902Y192217D03*
X471839Y204028D03*
X467902Y215839D03*
Y207965D03*
Y211902D03*
Y200091D03*
X471839D03*
X467902Y204028D03*
X471839Y207965D03*
Y211902D03*
Y215839D03*
G54D80*
X529108Y330600D03*
X555092D03*
G54D53*
X323744Y286500D03*
Y276500D03*
X344256Y286500D03*
Y276500D03*
X550544Y262100D03*
Y282100D03*
Y272100D03*
Y292100D03*
Y302100D03*
X571056Y262100D03*
Y282100D03*
Y272100D03*
Y302100D03*
Y292100D03*
X601844Y261500D03*
Y281500D03*
Y271500D03*
Y291500D03*
Y301500D03*
X622356Y261500D03*
Y281500D03*
Y271500D03*
Y301500D03*
Y291500D03*
G54D35*
X162033Y297112D03*
X504833Y266312D03*
X556533Y63512D03*
G54D90*
X555607Y363305D03*
G54D72*
X404890Y395263D03*
Y397231D03*
Y399200D03*
Y401169D03*
Y403137D03*
X423910D03*
Y401169D03*
Y399200D03*
Y397231D03*
Y395263D03*
G54D18*
X57100Y389900D03*
Y384500D03*
X145500Y313800D03*
Y319200D03*
X176000Y313300D03*
Y318700D03*
X349100Y250900D03*
Y256300D03*
X493300Y252000D03*
Y246600D03*
X512000Y390700D03*
Y385300D03*
X539500Y222900D03*
Y228300D03*
X570000Y93300D03*
Y98700D03*
G54D36*
X162033Y299531D03*
Y301500D03*
Y303469D03*
X173967D03*
Y301500D03*
Y299531D03*
X504833Y268731D03*
X516767D03*
X504833Y270700D03*
Y272669D03*
X516767D03*
Y270700D03*
X556533Y69869D03*
X568467D03*
X556533Y67900D03*
Y65931D03*
X568467Y67900D03*
Y65931D03*
G54D63*
X389231Y288533D03*
Y300467D03*
X391200Y288533D03*
X393169D03*
X391200Y300467D03*
X393169D03*
X596047Y214382D03*
X598016D03*
X599984D03*
X601953D03*
Y204418D03*
X599984D03*
X598016D03*
X596047D03*
G54D45*
X158104Y395616D03*
Y399553D03*
Y393647D03*
Y397584D03*
X341796Y402184D03*
Y398247D03*
Y404153D03*
Y400216D03*
G54D54*
X338016Y222296D03*
X339984D03*
X336047D03*
X339984Y240504D03*
X336047D03*
X338016D03*
X341953Y222296D03*
Y240504D03*
G54D81*
X528300Y415049D03*
Y420953D03*
X543504Y407875D03*
Y421654D03*
Y413779D03*
Y427558D03*
X567126Y407875D03*
X555315D03*
Y421654D03*
X567126Y413779D03*
X555315D03*
X567126Y421654D03*
X555315Y427558D03*
X567126D03*
X578937Y407875D03*
Y413779D03*
Y421654D03*
Y427558D03*
X590748Y407875D03*
X602559D03*
Y421654D03*
X590748Y413779D03*
X602559D03*
Y427558D03*
X614370Y407875D03*
Y421654D03*
Y413779D03*
Y427558D03*
G54D27*
X69300Y373600D03*
X87300D03*
G54D19*
X73662Y70850D03*
X76221D03*
X78780D03*
X73662Y94750D03*
X76221D03*
X78780D03*
X81339Y70850D03*
Y94750D03*
G54D28*
X95750Y65360D03*
Y72840D03*
Y69100D03*
X107050Y72840D03*
Y65360D03*
G54D82*
X552087Y209988D03*
Y212154D03*
Y214319D03*
X562913D03*
Y212154D03*
Y209988D03*
G54D55*
X332848Y230416D03*
Y226479D03*
Y228447D03*
Y224510D03*
Y222542D03*
Y232384D03*
Y236321D03*
Y238290D03*
Y240258D03*
Y234353D03*
X345152Y230416D03*
Y228447D03*
Y226479D03*
Y224510D03*
Y222542D03*
Y232384D03*
Y234353D03*
Y236321D03*
Y238290D03*
Y240258D03*
G54D73*
X429225Y282679D03*
Y284647D03*
Y286616D03*
Y288584D03*
Y290553D03*
Y292521D03*
X441975Y284647D03*
Y292521D03*
Y290553D03*
Y288584D03*
Y286616D03*
G54D37*
X162033Y305888D03*
X504833Y275088D03*
X556533Y72288D03*
G54D64*
X386812Y288533D03*
G54D91*
X553600Y364025D03*
G54D46*
X173967Y297112D03*
X516767Y266312D03*
X568467Y63512D03*
G54D83*
X552087Y216878D03*
X562913D03*
G54D74*
X431400Y90634D03*
X441400D03*
X436400D03*
X431400Y82366D03*
X436400D03*
X441400D03*
G54D92*
X551631Y383456D03*
X555569D03*
G54D29*
X89848Y263200D03*
X95248D03*
X158800Y377600D03*
X153400D03*
X341100Y420200D03*
X346500D03*
X361800Y147000D03*
X367200D03*
X362800Y220500D03*
X368200D03*
X370800Y309900D03*
X365400D03*
X459800Y386000D03*
X465200D03*
X523700Y172500D03*
X518300D03*
X531400Y390200D03*
X547900Y356900D03*
X536800Y390200D03*
X553300Y356900D03*
X603300Y232400D03*
X608700D03*
G54D47*
X173967Y305888D03*
X516767Y275088D03*
X568467Y72288D03*
G54D65*
X386812Y300467D03*
G54D38*
X159669Y317000D03*
Y327000D03*
X168331Y317000D03*
Y327000D03*
G54D56*
X350595Y189187D03*
X358207Y192336D03*
Y193911D03*
Y189187D03*
Y190762D03*
X350595Y193911D03*
Y190762D03*
Y192336D03*
G54D93*
X599450Y127063D03*
Y137063D03*
Y147063D03*
Y157063D03*
Y167063D03*
Y177063D03*
G54D39*
X167800Y377600D03*
X164800Y415100D03*
X182200Y310500D03*
X184800Y326000D03*
X178200D03*
X174400Y377600D03*
X171400Y415100D03*
X188800Y310500D03*
X325500Y420200D03*
X328500Y382700D03*
X335100D03*
X332100Y420200D03*
X373200Y106000D03*
X379800D03*
X413400Y285500D03*
X420000D03*
X413400Y293600D03*
X420000D03*
X458800Y392700D03*
X465400D03*
X493300Y126400D03*
X499900D03*
X516200Y252100D03*
X508000Y253400D03*
X501400D03*
X527300Y124000D03*
X520700D03*
X522800Y252100D03*
X529800Y382700D03*
X548400Y86300D03*
X536400Y382700D03*
X563200Y85900D03*
X555000Y86300D03*
X565700Y161000D03*
X569800Y85900D03*
X572300Y161000D03*
G54D75*
X441975Y282429D03*
G54D84*
X551004Y219240D03*
X563996D03*
G54D48*
X184387Y397600D03*
X207813D03*
G54D57*
X355189Y188543D03*
X353614D03*
X355189Y194555D03*
X353614D03*
G54D66*
X395588Y300467D03*
G54D76*
X447200Y353150D03*
X439800D03*
X443500Y361850D03*
G54D58*
X357000Y233243D03*
Y238557D03*
G54D49*
X275400Y57941D03*
X284800D03*
Y63059D03*
X275400D03*
Y60500D03*
G54D85*
X547929Y365826D03*
Y367794D03*
Y369763D03*
Y371731D03*
Y373700D03*
Y375669D03*
Y377637D03*
Y379606D03*
Y381574D03*
X559271Y371731D03*
Y369763D03*
Y367794D03*
Y365826D03*
Y381574D03*
Y379606D03*
Y377637D03*
Y375669D03*
Y373700D03*
G54D94*
X608450Y100660D03*
Y108340D03*
Y105780D03*
Y103220D03*
X626550Y108340D03*
Y100660D03*
Y103220D03*
Y105780D03*
G54D67*
X395588Y288533D03*
G54D95*
X614648Y127063D03*
Y137063D03*
Y147063D03*
Y157063D03*
Y167063D03*
Y177063D03*
G54D86*
X559700Y173072D03*
Y194529D03*
G54D68*
X400559Y340560D03*
X398000D03*
X395441D03*
Y348040D03*
X398000D03*
X400559D03*
X420059Y340760D03*
X417500D03*
X414941D03*
Y348240D03*
X417500D03*
X420059D03*
G54D59*
X348100Y323500D03*
Y328500D03*
Y338500D03*
Y333500D03*
X376900D03*
Y338500D03*
Y323500D03*
Y328500D03*
G54D77*
X474000Y243650D03*
Y254150D03*
G54D96*
X651582Y214961D03*
Y207087D03*
G54D78*
X478656Y367205D03*
Y375079D03*
Y382953D03*
Y390827D03*
X491549Y367205D03*
Y375079D03*
Y382953D03*
Y390827D03*
G54D69*
X410463Y389690D03*
Y408710D03*
X418337Y389690D03*
X416369D03*
X414400D03*
X412431D03*
Y408710D03*
X414400D03*
X416369D03*
X418337D03*
G54D87*
X558780Y213138D03*
X556220D03*
G54D97*
X641050Y216142D03*
Y213583D03*
Y211024D03*
Y208465D03*
Y205906D03*
G54D88*
X556516Y221996D03*
X560453D03*
X554547D03*
X558484D03*
G54D79*
X529750Y147000D03*
X519250D03*
X529750Y134500D03*
X519250D03*
X529750Y159500D03*
X519250D03*
G54D98*
G01X136000Y-65500D02*
Y-158000D01*
X506000D01*
Y-65500D01*
X136000D01*
G01X316000D02*
Y-158000D01*
G54D89*
X562913Y221996D03*
X552087D03*
G54D99*
G01X329433Y-125500D02*
Y-133000D01*
X333167D01*
G01X340480D02*
Y-128000D01*
G01Y-128875D02*
X340107Y-128375D01*
X339547Y-128125D01*
X338893Y-128000D01*
X338240Y-128250D01*
X337680Y-128750D01*
X337307Y-129500D01*
X337120Y-130500D01*
X337307Y-131500D01*
X337680Y-132250D01*
X338240Y-132750D01*
X338893Y-133000D01*
X339547Y-132875D01*
X340107Y-132500D01*
X340480Y-132000D01*
G01X344340Y-135250D02*
X344900Y-135500D01*
X345647Y-135250D01*
X346113Y-134750D01*
X346487Y-134125D01*
X347047Y-132125D01*
X348260Y-128000D01*
G01X345273D02*
X347047Y-132125D01*
G01X352400Y-129625D02*
X355387D01*
X355107Y-128750D01*
X354640Y-128250D01*
X353987Y-128000D01*
X353333Y-128125D01*
X352773Y-128500D01*
X352400Y-129375D01*
X352213Y-130125D01*
Y-130875D01*
X352400Y-131625D01*
X352867Y-132375D01*
X353427Y-132875D01*
X354080Y-133000D01*
X354733Y-132750D01*
X355387Y-132000D01*
G01X359993Y-133000D02*
Y-128000D01*
G01Y-129000D02*
X360460Y-128500D01*
X360927Y-128125D01*
X361580Y-128000D01*
X362047Y-128125D01*
X362607Y-128500D01*
G01X368800Y-133250D02*
X368613Y-133125D01*
Y-132875D01*
X368800Y-132750D01*
X368987Y-132875D01*
Y-133125D01*
X368800Y-133250D01*
G01Y-129875D02*
X368613Y-129750D01*
Y-129500D01*
X368800Y-129375D01*
X368987Y-129500D01*
Y-129750D01*
X368800Y-129875D01*
G01X336747Y-120500D02*
Y-113000D01*
X338613D01*
X339360Y-113375D01*
X339920Y-113875D01*
X340387Y-114625D01*
X340760Y-115500D01*
X340853Y-116750D01*
X340760Y-118000D01*
X340387Y-118875D01*
X339920Y-119625D01*
X339360Y-120125D01*
X338613Y-120500D01*
X336747D01*
G01X347980D02*
Y-115500D01*
G01Y-116375D02*
X347607Y-115875D01*
X347047Y-115625D01*
X346393Y-115500D01*
X345740Y-115750D01*
X345180Y-116250D01*
X344807Y-117000D01*
X344620Y-118000D01*
X344807Y-119000D01*
X345180Y-119750D01*
X345740Y-120250D01*
X346393Y-120500D01*
X347047Y-120375D01*
X347607Y-120000D01*
X347980Y-119500D01*
G01X353800Y-113000D02*
Y-120500D01*
G01X352493Y-115500D02*
X355107D01*
G01X359900Y-117125D02*
X362887D01*
X362607Y-116250D01*
X362140Y-115750D01*
X361487Y-115500D01*
X360833Y-115625D01*
X360273Y-116000D01*
X359900Y-116875D01*
X359713Y-117625D01*
Y-118375D01*
X359900Y-119125D01*
X360367Y-119875D01*
X360927Y-120375D01*
X361580Y-120500D01*
X362233Y-120250D01*
X362887Y-119500D01*
G01X368800Y-120750D02*
X368613Y-120625D01*
Y-120375D01*
X368800Y-120250D01*
X368987Y-120375D01*
Y-120625D01*
X368800Y-120750D01*
G01Y-117375D02*
X368613Y-117250D01*
Y-117000D01*
X368800Y-116875D01*
X368987Y-117000D01*
Y-117250D01*
X368800Y-117375D01*
G01X382027Y-114250D02*
X382587Y-113500D01*
X383240Y-113125D01*
X383987Y-113000D01*
X384920Y-113250D01*
X385573Y-113875D01*
X385760Y-114625D01*
X385667Y-115375D01*
X385293Y-116000D01*
X383427Y-117250D01*
X382587Y-118125D01*
X382027Y-119375D01*
X381840Y-120500D01*
X385760D01*
G01X391300Y-113000D02*
X390553Y-113250D01*
X389993Y-113875D01*
X389620Y-114625D01*
X389340Y-115625D01*
X389247Y-116750D01*
X389340Y-117875D01*
X389620Y-118875D01*
X389993Y-119625D01*
X390553Y-120250D01*
X391300Y-120500D01*
X392047Y-120250D01*
X392607Y-119625D01*
X392980Y-118875D01*
X393260Y-117875D01*
X393353Y-116750D01*
X393260Y-115625D01*
X392980Y-114625D01*
X392607Y-113875D01*
X392047Y-113250D01*
X391300Y-113000D01*
G01X397027Y-114250D02*
X397587Y-113500D01*
X398240Y-113125D01*
X398987Y-113000D01*
X399920Y-113250D01*
X400573Y-113875D01*
X400760Y-114625D01*
X400667Y-115375D01*
X400293Y-116000D01*
X398427Y-117250D01*
X397587Y-118125D01*
X397027Y-119375D01*
X396840Y-120500D01*
X400760D01*
G01X404527Y-114250D02*
X405087Y-113500D01*
X405740Y-113125D01*
X406487Y-113000D01*
X407420Y-113250D01*
X408073Y-113875D01*
X408260Y-114625D01*
X408167Y-115375D01*
X407793Y-116000D01*
X405927Y-117250D01*
X405087Y-118125D01*
X404527Y-119375D01*
X404340Y-120500D01*
X408260D01*
G01X412587Y-118000D02*
X415013D01*
G01X421300Y-113000D02*
X420553Y-113250D01*
X419993Y-113875D01*
X419620Y-114625D01*
X419340Y-115625D01*
X419247Y-116750D01*
X419340Y-117875D01*
X419620Y-118875D01*
X419993Y-119625D01*
X420553Y-120250D01*
X421300Y-120500D01*
X422047Y-120250D01*
X422607Y-119625D01*
X422980Y-118875D01*
X423260Y-117875D01*
X423353Y-116750D01*
X423260Y-115625D01*
X422980Y-114625D01*
X422607Y-113875D01*
X422047Y-113250D01*
X421300Y-113000D01*
G01X427027Y-114250D02*
X427587Y-113500D01*
X428240Y-113125D01*
X428987Y-113000D01*
X429920Y-113250D01*
X430573Y-113875D01*
X430760Y-114625D01*
X430667Y-115375D01*
X430293Y-116000D01*
X428427Y-117250D01*
X427587Y-118125D01*
X427027Y-119375D01*
X426840Y-120500D01*
X430760D01*
G01X435087Y-118000D02*
X437513D01*
G01X442027Y-114250D02*
X442587Y-113500D01*
X443240Y-113125D01*
X443987Y-113000D01*
X444920Y-113250D01*
X445573Y-113875D01*
X445760Y-114625D01*
X445667Y-115375D01*
X445293Y-116000D01*
X443427Y-117250D01*
X442587Y-118125D01*
X442027Y-119375D01*
X441840Y-120500D01*
X445760D01*
G01X449247Y-119375D02*
X449807Y-120000D01*
X450460Y-120375D01*
X451300Y-120500D01*
X452140Y-120250D01*
X452793Y-119750D01*
X453260Y-118875D01*
X453353Y-117875D01*
X453167Y-116875D01*
X452700Y-116250D01*
X452047Y-115750D01*
X451393Y-115625D01*
X450740Y-115750D01*
X449900Y-116250D01*
X450180Y-113000D01*
X452700D01*
G01X336933Y-108000D02*
Y-100500D01*
X339267D01*
X340013Y-100875D01*
X340480Y-101375D01*
X340667Y-102375D01*
X340480Y-103375D01*
X339920Y-104000D01*
X339267Y-104375D01*
X336933D01*
G01X339267D02*
X340667Y-108000D01*
G01X344900Y-104625D02*
X347887D01*
X347607Y-103750D01*
X347140Y-103250D01*
X346487Y-103000D01*
X345833Y-103125D01*
X345273Y-103500D01*
X344900Y-104375D01*
X344713Y-105125D01*
Y-105875D01*
X344900Y-106625D01*
X345367Y-107375D01*
X345927Y-107875D01*
X346580Y-108000D01*
X347233Y-107750D01*
X347887Y-107000D01*
G01X352120Y-103000D02*
X353800Y-108000D01*
X355480Y-103000D01*
G01X368800Y-108250D02*
X368613Y-108125D01*
Y-107875D01*
X368800Y-107750D01*
X368987Y-107875D01*
Y-108125D01*
X368800Y-108250D01*
G01Y-104875D02*
X368613Y-104750D01*
Y-104500D01*
X368800Y-104375D01*
X368987Y-104500D01*
Y-104750D01*
X368800Y-104875D01*
G01X383800Y-100500D02*
X383053Y-100750D01*
X382493Y-101375D01*
X382120Y-102125D01*
X381840Y-103125D01*
X381747Y-104250D01*
X381840Y-105375D01*
X382120Y-106375D01*
X382493Y-107125D01*
X383053Y-107750D01*
X383800Y-108000D01*
X384547Y-107750D01*
X385107Y-107125D01*
X385480Y-106375D01*
X385760Y-105375D01*
X385853Y-104250D01*
X385760Y-103125D01*
X385480Y-102125D01*
X385107Y-101375D01*
X384547Y-100750D01*
X383800Y-100500D01*
G01X391300Y-108000D02*
Y-100500D01*
X390180Y-102000D01*
G01Y-108000D02*
X392420D01*
G01X336933Y-95500D02*
Y-88000D01*
X339173D01*
X339920Y-88375D01*
X340480Y-89250D01*
X340667Y-90250D01*
X340480Y-91250D01*
X340013Y-92000D01*
X339173Y-92375D01*
X336933D01*
G01X344620Y-95750D02*
X347980Y-88000D01*
G01X351653Y-95500D02*
Y-88000D01*
X355947Y-95500D01*
Y-88000D01*
G01X368800Y-95750D02*
X368613Y-95625D01*
Y-95375D01*
X368800Y-95250D01*
X368987Y-95375D01*
Y-95625D01*
X368800Y-95750D01*
G01Y-92375D02*
X368613Y-92250D01*
Y-92000D01*
X368800Y-91875D01*
X368987Y-92000D01*
Y-92250D01*
X368800Y-92375D01*
G01X381933Y-95500D02*
Y-88000D01*
X384267D01*
X385013Y-88375D01*
X385480Y-88875D01*
X385667Y-89875D01*
X385480Y-90875D01*
X384920Y-91500D01*
X384267Y-91875D01*
X381933D01*
G01X384267D02*
X385667Y-95500D01*
G01X392420D02*
Y-88000D01*
X388967Y-93375D01*
X393633D01*
G01X398800Y-88000D02*
X398053Y-88250D01*
X397493Y-88875D01*
X397120Y-89625D01*
X396840Y-90625D01*
X396747Y-91750D01*
X396840Y-92875D01*
X397120Y-93875D01*
X397493Y-94625D01*
X398053Y-95250D01*
X398800Y-95500D01*
X399547Y-95250D01*
X400107Y-94625D01*
X400480Y-93875D01*
X400760Y-92875D01*
X400853Y-91750D01*
X400760Y-90625D01*
X400480Y-89625D01*
X400107Y-88875D01*
X399547Y-88250D01*
X398800Y-88000D01*
G01X406300D02*
X405553Y-88250D01*
X404993Y-88875D01*
X404620Y-89625D01*
X404340Y-90625D01*
X404247Y-91750D01*
X404340Y-92875D01*
X404620Y-93875D01*
X404993Y-94625D01*
X405553Y-95250D01*
X406300Y-95500D01*
X407047Y-95250D01*
X407607Y-94625D01*
X407980Y-93875D01*
X408260Y-92875D01*
X408353Y-91750D01*
X408260Y-90625D01*
X407980Y-89625D01*
X407607Y-88875D01*
X407047Y-88250D01*
X406300Y-88000D01*
G01X412027Y-92375D02*
X412680Y-91500D01*
X413240Y-91000D01*
X413987Y-90750D01*
X414640Y-91000D01*
X415107Y-91500D01*
X415480Y-92250D01*
X415573Y-93125D01*
X415480Y-93875D01*
X415107Y-94625D01*
X414547Y-95250D01*
X413893Y-95500D01*
X413147Y-95250D01*
X412493Y-94500D01*
X412120Y-93375D01*
X412027Y-92125D01*
X412213Y-90500D01*
X412493Y-89625D01*
X412960Y-88750D01*
X413613Y-88125D01*
X414267Y-88000D01*
X414920Y-88250D01*
X415387Y-88875D01*
G01X420087Y-93000D02*
X422513D01*
G01X429547Y-91500D02*
X429920Y-91125D01*
X430200Y-90500D01*
X430387Y-89625D01*
X430200Y-88875D01*
X429827Y-88375D01*
X429173Y-88000D01*
X426653D01*
Y-95500D01*
X429733D01*
X430387Y-95000D01*
X430760Y-94250D01*
X430947Y-93375D01*
X430760Y-92500D01*
X430200Y-91750D01*
X429547Y-91500D01*
X426653D01*
G01X436300Y-88000D02*
X435553Y-88250D01*
X434993Y-88875D01*
X434620Y-89625D01*
X434340Y-90625D01*
X434247Y-91750D01*
X434340Y-92875D01*
X434620Y-93875D01*
X434993Y-94625D01*
X435553Y-95250D01*
X436300Y-95500D01*
X437047Y-95250D01*
X437607Y-94625D01*
X437980Y-93875D01*
X438260Y-92875D01*
X438353Y-91750D01*
X438260Y-90625D01*
X437980Y-89625D01*
X437607Y-88875D01*
X437047Y-88250D01*
X436300Y-88000D01*
G01X443800D02*
X443053Y-88250D01*
X442493Y-88875D01*
X442120Y-89625D01*
X441840Y-90625D01*
X441747Y-91750D01*
X441840Y-92875D01*
X442120Y-93875D01*
X442493Y-94625D01*
X443053Y-95250D01*
X443800Y-95500D01*
X444547Y-95250D01*
X445107Y-94625D01*
X445480Y-93875D01*
X445760Y-92875D01*
X445853Y-91750D01*
X445760Y-90625D01*
X445480Y-89625D01*
X445107Y-88875D01*
X444547Y-88250D01*
X443800Y-88000D01*
G01X451300D02*
X450553Y-88250D01*
X449993Y-88875D01*
X449620Y-89625D01*
X449340Y-90625D01*
X449247Y-91750D01*
X449340Y-92875D01*
X449620Y-93875D01*
X449993Y-94625D01*
X450553Y-95250D01*
X451300Y-95500D01*
X452047Y-95250D01*
X452607Y-94625D01*
X452980Y-93875D01*
X453260Y-92875D01*
X453353Y-91750D01*
X453260Y-90625D01*
X452980Y-89625D01*
X452607Y-88875D01*
X452047Y-88250D01*
X451300Y-88000D01*
G01X458800Y-95500D02*
Y-88000D01*
X457680Y-89500D01*
G01Y-95500D02*
X459920D01*
G01X465087Y-93000D02*
X467513D01*
G01X473800Y-88000D02*
X473053Y-88250D01*
X472493Y-88875D01*
X472120Y-89625D01*
X471840Y-90625D01*
X471747Y-91750D01*
X471840Y-92875D01*
X472120Y-93875D01*
X472493Y-94625D01*
X473053Y-95250D01*
X473800Y-95500D01*
X474547Y-95250D01*
X475107Y-94625D01*
X475480Y-93875D01*
X475760Y-92875D01*
X475853Y-91750D01*
X475760Y-90625D01*
X475480Y-89625D01*
X475107Y-88875D01*
X474547Y-88250D01*
X473800Y-88000D01*
G01X479527Y-89250D02*
X480087Y-88500D01*
X480740Y-88125D01*
X481487Y-88000D01*
X482420Y-88250D01*
X483073Y-88875D01*
X483260Y-89625D01*
X483167Y-90375D01*
X482793Y-91000D01*
X480927Y-92250D01*
X480087Y-93125D01*
X479527Y-94375D01*
X479340Y-95500D01*
X483260D01*
G01X381840Y-132000D02*
X382587Y-132625D01*
X383427Y-133000D01*
X384173D01*
X384920Y-132625D01*
X385480Y-132000D01*
X385760Y-131125D01*
X385573Y-130250D01*
X385107Y-129500D01*
X384267Y-129000D01*
X383147Y-128750D01*
X382493Y-128250D01*
X382213Y-127375D01*
X382400Y-126500D01*
X382867Y-125875D01*
X383520Y-125500D01*
X384173D01*
X384827Y-125750D01*
X385387Y-126375D01*
G01X391300Y-133000D02*
X390553Y-132875D01*
X389900Y-132375D01*
X389340Y-131625D01*
X388967Y-130750D01*
X388780Y-129750D01*
Y-128750D01*
X388967Y-127750D01*
X389340Y-126875D01*
X389900Y-126125D01*
X390553Y-125625D01*
X391300Y-125500D01*
X392047Y-125625D01*
X392700Y-126125D01*
X393260Y-126875D01*
X393633Y-127750D01*
X393820Y-128750D01*
Y-129750D01*
X393633Y-130750D01*
X393260Y-131625D01*
X392700Y-132375D01*
X392047Y-132875D01*
X391300Y-133000D01*
G01X396933Y-125500D02*
Y-133000D01*
X400667D01*
G01X404247D02*
Y-125500D01*
X406113D01*
X406860Y-125875D01*
X407420Y-126375D01*
X407887Y-127125D01*
X408260Y-128000D01*
X408353Y-129250D01*
X408260Y-130500D01*
X407887Y-131375D01*
X407420Y-132125D01*
X406860Y-132625D01*
X406113Y-133000D01*
X404247D01*
G01X415667D02*
X411933D01*
Y-125500D01*
X415667D01*
G01X414173Y-129125D02*
X411933D01*
G01X419433Y-133000D02*
Y-125500D01*
X421767D01*
X422513Y-125875D01*
X422980Y-126375D01*
X423167Y-127375D01*
X422980Y-128375D01*
X422420Y-129000D01*
X421767Y-129375D01*
X419433D01*
G01X421767D02*
X423167Y-133000D01*
G01X426933D02*
Y-125500D01*
X429173D01*
X429920Y-125875D01*
X430480Y-126750D01*
X430667Y-127750D01*
X430480Y-128750D01*
X430013Y-129500D01*
X429173Y-129875D01*
X426933D01*
G01X433967Y-133000D02*
X436300Y-125500D01*
X438633Y-133000D01*
G01X437793Y-130375D02*
X434807D01*
G01X441840Y-132000D02*
X442587Y-132625D01*
X443427Y-133000D01*
X444173D01*
X444920Y-132625D01*
X445480Y-132000D01*
X445760Y-131125D01*
X445573Y-130250D01*
X445107Y-129500D01*
X444267Y-129000D01*
X443147Y-128750D01*
X442493Y-128250D01*
X442213Y-127375D01*
X442400Y-126500D01*
X442867Y-125875D01*
X443520Y-125500D01*
X444173D01*
X444827Y-125750D01*
X445387Y-126375D01*
G01X451300Y-125500D02*
Y-133000D01*
G01X449153Y-125500D02*
X453447D01*
G01X460667Y-133000D02*
X456933D01*
Y-125500D01*
X460667D01*
G01X459173Y-129125D02*
X456933D01*
G01X473800Y-125500D02*
Y-133000D01*
G01X471653Y-125500D02*
X475947D01*
G01X481300Y-133000D02*
X480553Y-132875D01*
X479900Y-132375D01*
X479340Y-131625D01*
X478967Y-130750D01*
X478780Y-129750D01*
Y-128750D01*
X478967Y-127750D01*
X479340Y-126875D01*
X479900Y-126125D01*
X480553Y-125625D01*
X481300Y-125500D01*
X482047Y-125625D01*
X482700Y-126125D01*
X483260Y-126875D01*
X483633Y-127750D01*
X483820Y-128750D01*
Y-129750D01*
X483633Y-130750D01*
X483260Y-131625D01*
X482700Y-132375D01*
X482047Y-132875D01*
X481300Y-133000D01*
G01X486933D02*
Y-125500D01*
X489173D01*
X489920Y-125875D01*
X490480Y-126750D01*
X490667Y-127750D01*
X490480Y-128750D01*
X490013Y-129500D01*
X489173Y-129875D01*
X486933D01*
M02*
